FILE_TYPE = MACRO_DRAWING;
SET COLOR_WIRE YELLOW;
SET COLOR_PROP MONO;
SET COLOR_DOT WHITE;
SET COLOR_ARC YELLOW;
SET COLOR_BODY GREEN;
SET COLOR_NOTE MONO;
SET PROP_DISPLAY VALUE;
SET PAGE_NUMBER P71;
FORCEADD PVCCIN_CPU1..1
(-5425 4425);
FORCEPROP 3 LASTPIN (-5425 4375) SIG_NAME PVCCIN_CPU1\g
J 0
(-5415 4385);
DISPLAY 0.659574 (-5415 4385);
PAINT MONO (-5415 4385);
DISPLAY INVISIBLE (-5415 4385);
FORCEPROP 1 LAST VOLTAGE 2.0V
J 0
(-5470 4382);
DISPLAY 0.340426 (-5470 4382);
PAINT SKYBLUE (-5470 4382);
DISPLAY INVISIBLE (-5470 4382);
FORCEPROP 2 LAST CDS_LIB mstr_symbols
J 0
(-5425 4425);
PAINT ORANGE (-5425 4425);
DISPLAY INVISIBLE (-5425 4425);
FORCEPROP 1 LAST BODY_TYPE PLUMBING
J 0
(-5470 4382);
DISPLAY 0.340426 (-5470 4382);
PAINT GREEN (-5470 4382);
DISPLAY INVISIBLE (-5470 4382);
FORCEPROP 1 LAST HDL_POWER PVCCIN_CPU1
J 1
(-5425 4475);
DISPLAY 0.872340 (-5425 4475);
PAINT GREEN (-5425 4475);
DISPLAY INVISIBLE (-5425 4475);
FORCEPROP 1 LAST PATH I35
J 0
(-5375 4450);
DISPLAY 0.872340 (-5375 4450);
PAINT AQUA (-5375 4450);
DISPLAY INVISIBLE (-5375 4450);
FORCEADD PVCCIN_CPU1..1
(-7325 4400);
FORCEPROP 3 LASTPIN (-7325 4350) SIG_NAME PVCCIN_CPU1\g
J 0
(-7315 4360);
DISPLAY 0.659574 (-7315 4360);
PAINT MONO (-7315 4360);
DISPLAY INVISIBLE (-7315 4360);
FORCEPROP 1 LAST VOLTAGE 2.0V
J 0
(-7370 4357);
DISPLAY 0.340426 (-7370 4357);
PAINT SKYBLUE (-7370 4357);
DISPLAY INVISIBLE (-7370 4357);
FORCEPROP 2 LAST CDS_LIB mstr_symbols
J 0
(-7325 4400);
PAINT ORANGE (-7325 4400);
DISPLAY INVISIBLE (-7325 4400);
FORCEPROP 1 LAST BODY_TYPE PLUMBING
J 0
(-7370 4357);
DISPLAY 0.340426 (-7370 4357);
PAINT GREEN (-7370 4357);
DISPLAY INVISIBLE (-7370 4357);
FORCEPROP 1 LAST PATH I36
J 0
(-7275 4425);
DISPLAY 0.872340 (-7275 4425);
PAINT AQUA (-7275 4425);
DISPLAY INVISIBLE (-7275 4425);
FORCEPROP 1 LAST HDL_POWER PVCCIN_CPU1
J 1
(-7325 4450);
DISPLAY 0.872340 (-7325 4450);
PAINT GREEN (-7325 4450);
DISPLAY INVISIBLE (-7325 4450);
FORCEADD OFFPAGE..2
(-875 825);
FORCEPROP 2 LAST $XR0 209 
J 0
(-686 825);
DISPLAY 0.638298 (-686 825);
PAINT MONO (-686 825);
FORCEPROP 1 LAST COMMENT_BODY TRUE
J 0
(-920 730);
DISPLAY 1.170213 (-920 730);
PAINT GREEN (-920 730);
DISPLAY INVISIBLE (-920 730);
FORCEPROP 2 LAST CDS_LIB mstr_standard
J 0
(-875 825);
PAINT ORANGE (-875 825);
DISPLAY INVISIBLE (-875 825);
FORCEPROP 1 LAST OFFPAGE TRUE
J 0
(-550 700);
DISPLAY 1.170213 (-550 700);
PAINT GREEN (-550 700);
DISPLAY INVISIBLE (-550 700);
FORCEPROP 2 LAST PATH I38
J 0
(-700 900);
DISPLAY 1.021277 (-700 900);
PAINT ORANGE (-700 900);
DISPLAY INVISIBLE (-700 900);
FORCEADD OFFPAGE..2
(-875 775);
FORCEPROP 2 LAST $XR0 209 
J 0
(-686 775);
DISPLAY 0.638298 (-686 775);
PAINT MONO (-686 775);
FORCEPROP 1 LAST COMMENT_BODY TRUE
J 0
(-920 680);
DISPLAY 1.170213 (-920 680);
PAINT GREEN (-920 680);
DISPLAY INVISIBLE (-920 680);
FORCEPROP 2 LAST CDS_LIB mstr_standard
J 0
(-875 775);
PAINT ORANGE (-875 775);
DISPLAY INVISIBLE (-875 775);
FORCEPROP 1 LAST OFFPAGE TRUE
J 0
(-550 650);
DISPLAY 1.170213 (-550 650);
PAINT GREEN (-550 650);
DISPLAY INVISIBLE (-550 650);
FORCEPROP 2 LAST PATH I39
J 0
(-700 850);
DISPLAY 1.021277 (-700 850);
PAINT ORANGE (-700 850);
DISPLAY INVISIBLE (-700 850);
FORCEADD PVCCIN_CPU1..1
(-3600 4400);
FORCEPROP 3 LASTPIN (-3600 4350) SIG_NAME PVCCIN_CPU1\g
J 0
(-3590 4360);
DISPLAY 0.659574 (-3590 4360);
PAINT MONO (-3590 4360);
DISPLAY INVISIBLE (-3590 4360);
FORCEPROP 1 LAST VOLTAGE 2.0V
J 0
(-3645 4357);
DISPLAY 0.340426 (-3645 4357);
PAINT SKYBLUE (-3645 4357);
DISPLAY INVISIBLE (-3645 4357);
FORCEPROP 2 LAST CDS_LIB mstr_symbols
J 0
(-3600 4400);
PAINT ORANGE (-3600 4400);
DISPLAY INVISIBLE (-3600 4400);
FORCEPROP 1 LAST BODY_TYPE PLUMBING
J 0
(-3645 4357);
DISPLAY 0.340426 (-3645 4357);
PAINT GREEN (-3645 4357);
DISPLAY INVISIBLE (-3645 4357);
FORCEPROP 1 LAST HDL_POWER PVCCIN_CPU1
J 1
(-3600 4450);
DISPLAY 0.872340 (-3600 4450);
PAINT GREEN (-3600 4450);
DISPLAY INVISIBLE (-3600 4450);
FORCEPROP 1 LAST PATH I40
J 0
(-3550 4425);
DISPLAY 0.872340 (-3550 4425);
PAINT AQUA (-3550 4425);
DISPLAY INVISIBLE (-3550 4425);
FORCEADD PVCCIN_CPU1..1
(-1725 4375);
FORCEPROP 3 LASTPIN (-1725 4325) SIG_NAME PVCCIN_CPU1\g
J 0
(-1715 4335);
DISPLAY 0.659574 (-1715 4335);
PAINT MONO (-1715 4335);
DISPLAY INVISIBLE (-1715 4335);
FORCEPROP 1 LAST VOLTAGE 2.0V
J 0
(-1770 4332);
DISPLAY 0.340426 (-1770 4332);
PAINT SKYBLUE (-1770 4332);
DISPLAY INVISIBLE (-1770 4332);
FORCEPROP 1 LAST BODY_TYPE PLUMBING
J 0
(-1770 4332);
DISPLAY 0.340426 (-1770 4332);
PAINT GREEN (-1770 4332);
DISPLAY INVISIBLE (-1770 4332);
FORCEPROP 2 LAST CDS_LIB mstr_symbols
J 0
(-1725 4375);
PAINT ORANGE (-1725 4375);
DISPLAY INVISIBLE (-1725 4375);
FORCEPROP 1 LAST PATH I41
J 0
(-1675 4400);
DISPLAY 0.872340 (-1675 4400);
PAINT AQUA (-1675 4400);
DISPLAY INVISIBLE (-1675 4400);
FORCEPROP 1 LAST HDL_POWER PVCCIN_CPU1
J 1
(-1725 4425);
DISPLAY 0.872340 (-1725 4425);
PAINT GREEN (-1725 4425);
DISPLAY INVISIBLE (-1725 4425);
FORCEADD GND..1
(-500 525);
FORCEPROP 3 LASTPIN (-500 575) SIG_NAME GND\g
J 0
(-490 585);
DISPLAY 0.659574 (-490 585);
PAINT MONO (-490 585);
DISPLAY INVISIBLE (-490 585);
FORCEPROP 1 LAST BODY_TYPE PLUMBING
J 0
(-545 482);
DISPLAY 0.340426 (-545 482);
PAINT GREEN (-545 482);
DISPLAY INVISIBLE (-545 482);
FORCEPROP 1 LAST VOLTAGE 0.0V
J 0
(-545 482);
DISPLAY 0.340426 (-545 482);
PAINT SKYBLUE (-545 482);
DISPLAY INVISIBLE (-545 482);
FORCEPROP 1 LAST SIZE 1B
J 0
(-425 475);
DISPLAY 1.170213 (-425 475);
PAINT AQUA (-425 475);
DISPLAY INVISIBLE (-425 475);
FORCEPROP 2 LAST CDS_LIB mstr_symbols
J 0
(-500 525);
PAINT ORANGE (-500 525);
DISPLAY INVISIBLE (-500 525);
FORCEPROP 1 LAST PATH I42
J 0
(-425 525);
DISPLAY 0.872340 (-425 525);
PAINT AQUA (-425 525);
DISPLAY INVISIBLE (-425 525);
FORCEPROP 1 LAST HDL_POWER GND
J 0
(-500 675);
DISPLAY 1.170213 (-500 675);
PAINT GREEN (-500 675);
DISPLAY INVISIBLE (-500 675);
FORCEADD RES..2
(-500 750);
FORCEPROP 1 LASTPIN (-500 650) $PN 2
J 0
(-495 660);
DISPLAY 0.617021 (-495 660);
PAINT ORANGE (-495 660);
FORCEPROP 1 LAST PACK_TYPE 0402
J 0
(-460 575);
DISPLAY 0.617021 (-460 575);
PAINT SKYBLUE (-460 575);
FORCEPROP 1 LAST MATERIAL CHIP
J 0
(-460 675);
DISPLAY 0.617021 (-460 675);
PAINT SKYBLUE (-460 675);
FORCEPROP 1 LAST WATTAGE 1/16W
J 0
(-460 725);
DISPLAY 0.617021 (-460 725);
PAINT SKYBLUE (-460 725);
FORCEPROP 1 LASTPIN (-500 850) $PN 1
J 0
(-495 812);
DISPLAY 0.617021 (-495 812);
PAINT ORANGE (-495 812);
FORCEPROP 1 LAST LOCATION R3D27
J 0
(-455 875);
DISPLAY 0.617021 (-455 875);
PAINT AQUA (-455 875);
FORCEPROP 1 LAST VALUE 249
J 0
(-455 825);
DISPLAY 0.617021 (-455 825);
PAINT SKYBLUE (-455 825);
FORCEPROP 1 LAST TOLERANCE 0.1%
J 0
(-455 775);
DISPLAY 0.617021 (-455 775);
PAINT SKYBLUE (-455 775);
FORCEPROP 1 LAST PART_NUMBER G85996-031
J 0
(-460 625);
DISPLAY 0.617021 (-460 625);
PAINT BLUE (-460 625);
FORCEPROP 2 LAST CDS_LIB mstr_discrete
J 0
(-500 750);
PAINT ORANGE (-500 750);
DISPLAY INVISIBLE (-500 750);
FORCEPROP 2 LAST CDS_LOCATION R3D27
J 0
(-455 875);
DISPLAY 0.617021 (-455 875);
PAINT AQUA (-455 875);
DISPLAY INVISIBLE (-455 875);
FORCEPROP 2 LAST ROOM CPU1
J 0
(-450 925);
PAINT MONO (-450 925);
DISPLAY INVISIBLE (-450 925);
FORCEPROP 1 LAST PATH I43
J 0
(-450 925);
DISPLAY 0.978723 (-450 925);
PAINT WHITE (-450 925);
DISPLAY INVISIBLE (-450 925);
FORCEPROP 2 LAST SEC 1
J 0
(-450 975);
DISPLAY 0.680851 (-450 975);
PAINT MONO (-450 975);
DISPLAY INVISIBLE (-450 975);
FORCEPROP 2 LAST BOM_COST PROC_SOCKET
J 0
(-450 975);
PAINT MONO (-450 975);
DISPLAY INVISIBLE (-450 975);
FORCEPROP 2 LAST SEC_TYPE 0402
J 0
(-450 975);
DISPLAY 1.021277 (-450 975);
PAINT ORANGE (-450 975);
DISPLAY INVISIBLE (-450 975);
FORCEADD PVCCIN_CPU1..1
(-1100 1700);
FORCEPROP 3 LASTPIN (-1100 1650) SIG_NAME PVCCIN_CPU1\g
J 0
(-1090 1660);
DISPLAY 0.659574 (-1090 1660);
PAINT MONO (-1090 1660);
DISPLAY INVISIBLE (-1090 1660);
FORCEPROP 1 LAST HDL_POWER PVCCIN_CPU1
J 1
(-1100 1750);
DISPLAY 0.872340 (-1100 1750);
PAINT GREEN (-1100 1750);
DISPLAY INVISIBLE (-1100 1750);
FORCEPROP 1 LAST PATH I45
J 0
(-1050 1725);
DISPLAY 0.872340 (-1050 1725);
PAINT AQUA (-1050 1725);
DISPLAY INVISIBLE (-1050 1725);
FORCEPROP 1 LAST BODY_TYPE PLUMBING
J 0
(-1145 1657);
DISPLAY 0.340426 (-1145 1657);
PAINT GREEN (-1145 1657);
DISPLAY INVISIBLE (-1145 1657);
FORCEPROP 2 LAST CDS_LIB mstr_symbols
J 0
(-1100 1700);
PAINT ORANGE (-1100 1700);
DISPLAY INVISIBLE (-1100 1700);
FORCEPROP 1 LAST VOLTAGE 2.0V
J 0
(-1145 1657);
DISPLAY 0.340426 (-1145 1657);
PAINT SKYBLUE (-1145 1657);
DISPLAY INVISIBLE (-1145 1657);
FORCEADD RES..2
(-1100 1400);
FORCEPROP 1 LASTPIN (-1100 1300) $PN 2
J 0
(-1095 1310);
DISPLAY 0.617021 (-1095 1310);
PAINT ORANGE (-1095 1310);
FORCEPROP 1 LASTPIN (-1100 1500) $PN 1
J 0
(-1095 1462);
DISPLAY 0.617021 (-1095 1462);
PAINT ORANGE (-1095 1462);
FORCEPROP 1 LAST WATTAGE 1/10W
J 0
(-1060 1375);
DISPLAY 0.617021 (-1060 1375);
PAINT SKYBLUE (-1060 1375);
FORCEPROP 1 LAST MATERIAL CHIP
J 0
(-1060 1325);
DISPLAY 0.617021 (-1060 1325);
PAINT SKYBLUE (-1060 1325);
FORCEPROP 1 LAST PACK_TYPE 0603
J 0
(-1060 1225);
DISPLAY 0.617021 (-1060 1225);
PAINT SKYBLUE (-1060 1225);
FORCEPROP 1 LAST TOLERANCE 1%
J 0
(-1055 1425);
DISPLAY 0.617021 (-1055 1425);
PAINT SKYBLUE (-1055 1425);
FORCEPROP 1 LAST VALUE 100.0K
J 0
(-1055 1475);
DISPLAY 0.617021 (-1055 1475);
PAINT SKYBLUE (-1055 1475);
FORCEPROP 1 LAST PART_NUMBER G22026-050
J 0
(-1060 1275);
DISPLAY 0.617021 (-1060 1275);
PAINT BLUE (-1060 1275);
FORCEPROP 1 LAST LOCATION RT8P1
J 0
(-1050 1525);
DISPLAY 0.617021 (-1050 1525);
PAINT AQUA (-1050 1525);
FORCEPROP 2 LAST CDS_LIB mstr_discrete
J 0
(-1100 1400);
PAINT ORANGE (-1100 1400);
DISPLAY INVISIBLE (-1100 1400);
FORCEPROP 2 LAST ROOM CPU1
J 0
(-1025 1500);
PAINT MONO (-1025 1500);
DISPLAY INVISIBLE (-1025 1500);
FORCEPROP 2 LAST CDS_LOCATION RT8P1
J 0
(-1050 1525);
DISPLAY 0.617021 (-1050 1525);
PAINT AQUA (-1050 1525);
DISPLAY INVISIBLE (-1050 1525);
FORCEPROP 1 LAST PATH I49
J 0
(-1050 1575);
DISPLAY 0.978723 (-1050 1575);
PAINT WHITE (-1050 1575);
DISPLAY INVISIBLE (-1050 1575);
FORCEPROP 2 LAST SEC 1
J 0
(-1050 1625);
DISPLAY 0.680851 (-1050 1625);
PAINT MONO (-1050 1625);
DISPLAY INVISIBLE (-1050 1625);
FORCEPROP 2 LAST SEC_TYPE 0603
J 0
(-1050 1625);
DISPLAY 1.021277 (-1050 1625);
PAINT ORANGE (-1050 1625);
DISPLAY INVISIBLE (-1050 1625);
FORCEPROP 2 LAST BOM_COST PROC_SOCKET
J 0
(-1025 1550);
PAINT MONO (-1025 1550);
DISPLAY INVISIBLE (-1025 1550);
FORCEADD SKX_EXT_B..18
(-6375 2525);
FORCEPROP 2 LASTPIN (-7075 825) $PN BF85
J 2
(-7085 835);
DISPLAY 0.617021 (-7085 835);
PAINT ORANGE (-7085 835);
FORCEPROP 2 LASTPIN (-7075 875) $PN BF83
J 2
(-7085 885);
DISPLAY 0.617021 (-7085 885);
PAINT ORANGE (-7085 885);
FORCEPROP 2 LASTPIN (-7075 925) $PN BF81
J 2
(-7085 935);
DISPLAY 0.617021 (-7085 935);
PAINT ORANGE (-7085 935);
FORCEPROP 2 LASTPIN (-7075 975) $PN BF79
J 2
(-7085 985);
DISPLAY 0.617021 (-7085 985);
PAINT ORANGE (-7085 985);
FORCEPROP 2 LASTPIN (-7075 1025) $PN BF77
J 2
(-7085 1035);
DISPLAY 0.617021 (-7085 1035);
PAINT ORANGE (-7085 1035);
FORCEPROP 2 LASTPIN (-7075 1075) $PN BF75
J 2
(-7085 1085);
DISPLAY 0.617021 (-7085 1085);
PAINT ORANGE (-7085 1085);
FORCEPROP 2 LASTPIN (-7075 1125) $PN BF73
J 2
(-7085 1135);
DISPLAY 0.617021 (-7085 1135);
PAINT ORANGE (-7085 1135);
FORCEPROP 2 LASTPIN (-7075 1175) $PN BF61
J 2
(-7085 1185);
DISPLAY 0.617021 (-7085 1185);
PAINT ORANGE (-7085 1185);
FORCEPROP 2 LASTPIN (-7075 1225) $PN BE84
J 2
(-7085 1235);
DISPLAY 0.617021 (-7085 1235);
PAINT ORANGE (-7085 1235);
FORCEPROP 2 LASTPIN (-7075 1275) $PN BE82
J 2
(-7085 1285);
DISPLAY 0.617021 (-7085 1285);
PAINT ORANGE (-7085 1285);
FORCEPROP 2 LASTPIN (-7075 1325) $PN BE80
J 2
(-7085 1335);
DISPLAY 0.617021 (-7085 1335);
PAINT ORANGE (-7085 1335);
FORCEPROP 2 LASTPIN (-7075 1375) $PN BE78
J 2
(-7085 1385);
DISPLAY 0.617021 (-7085 1385);
PAINT ORANGE (-7085 1385);
FORCEPROP 2 LASTPIN (-7075 1425) $PN BE76
J 2
(-7085 1435);
DISPLAY 0.617021 (-7085 1435);
PAINT ORANGE (-7085 1435);
FORCEPROP 2 LASTPIN (-7075 1475) $PN BE74
J 2
(-7085 1485);
DISPLAY 0.617021 (-7085 1485);
PAINT ORANGE (-7085 1485);
FORCEPROP 2 LASTPIN (-7075 1525) $PN BE72
J 2
(-7085 1535);
DISPLAY 0.617021 (-7085 1535);
PAINT ORANGE (-7085 1535);
FORCEPROP 2 LASTPIN (-7075 1575) $PN BE62
J 2
(-7085 1585);
DISPLAY 0.617021 (-7085 1585);
PAINT ORANGE (-7085 1585);
FORCEPROP 2 LASTPIN (-7075 1625) $PN BE60
J 2
(-7085 1635);
DISPLAY 0.617021 (-7085 1635);
PAINT ORANGE (-7085 1635);
FORCEPROP 2 LASTPIN (-7075 1675) $PN BD85
J 2
(-7085 1685);
DISPLAY 0.617021 (-7085 1685);
PAINT ORANGE (-7085 1685);
FORCEPROP 2 LASTPIN (-7075 1725) $PN BD83
J 2
(-7085 1735);
DISPLAY 0.617021 (-7085 1735);
PAINT ORANGE (-7085 1735);
FORCEPROP 2 LASTPIN (-7075 1775) $PN BD81
J 2
(-7085 1785);
DISPLAY 0.617021 (-7085 1785);
PAINT ORANGE (-7085 1785);
FORCEPROP 2 LASTPIN (-7075 1825) $PN BD79
J 2
(-7085 1835);
DISPLAY 0.617021 (-7085 1835);
PAINT ORANGE (-7085 1835);
FORCEPROP 2 LASTPIN (-7075 1875) $PN BD77
J 2
(-7085 1885);
DISPLAY 0.617021 (-7085 1885);
PAINT ORANGE (-7085 1885);
FORCEPROP 2 LASTPIN (-7075 1925) $PN BD75
J 2
(-7085 1935);
DISPLAY 0.617021 (-7085 1935);
PAINT ORANGE (-7085 1935);
FORCEPROP 2 LASTPIN (-7075 1975) $PN BD73
J 2
(-7085 1985);
DISPLAY 0.617021 (-7085 1985);
PAINT ORANGE (-7085 1985);
FORCEPROP 1 LAST PART_NUMBER TBD
J 0
(-7025 625);
DISPLAY 0.617021 (-7025 625);
PAINT BLUE (-7025 625);
FORCEPROP 2 LASTPIN (-7075 2025) $PN BD61
J 2
(-7085 2035);
DISPLAY 0.617021 (-7085 2035);
PAINT ORANGE (-7085 2035);
FORCEPROP 2 LASTPIN (-7075 2075) $PN BC84
J 2
(-7085 2085);
DISPLAY 0.617021 (-7085 2085);
PAINT ORANGE (-7085 2085);
FORCEPROP 2 LASTPIN (-7075 2125) $PN BC62
J 2
(-7085 2135);
DISPLAY 0.617021 (-7085 2135);
PAINT ORANGE (-7085 2135);
FORCEPROP 2 LASTPIN (-7075 2175) $PN BC60
J 2
(-7085 2185);
DISPLAY 0.617021 (-7085 2185);
PAINT ORANGE (-7085 2185);
FORCEPROP 2 LASTPIN (-7075 2225) $PN BB85
J 2
(-7085 2235);
DISPLAY 0.617021 (-7085 2235);
PAINT ORANGE (-7085 2235);
FORCEPROP 2 LASTPIN (-7075 2275) $PN BB61
J 2
(-7085 2285);
DISPLAY 0.617021 (-7085 2285);
PAINT ORANGE (-7085 2285);
FORCEPROP 2 LASTPIN (-7075 2325) $PN BA60
J 2
(-7085 2335);
DISPLAY 0.617021 (-7085 2335);
PAINT ORANGE (-7085 2335);
FORCEPROP 2 LASTPIN (-7075 2375) $PN AY61
J 2
(-7085 2385);
DISPLAY 0.617021 (-7085 2385);
PAINT ORANGE (-7085 2385);
FORCEPROP 2 LASTPIN (-7075 2425) $PN AW60
J 2
(-7085 2435);
DISPLAY 0.617021 (-7085 2435);
PAINT ORANGE (-7085 2435);
FORCEPROP 2 LASTPIN (-7075 2475) $PN AV61
J 2
(-7085 2485);
DISPLAY 0.617021 (-7085 2485);
PAINT ORANGE (-7085 2485);
FORCEPROP 2 LASTPIN (-7075 2525) $PN AV59
J 2
(-7085 2535);
DISPLAY 0.617021 (-7085 2535);
PAINT ORANGE (-7085 2535);
FORCEPROP 2 LASTPIN (-7075 2575) $PN AU60
J 2
(-7085 2585);
DISPLAY 0.617021 (-7085 2585);
PAINT ORANGE (-7085 2585);
FORCEPROP 2 LASTPIN (-7075 2625) $PN AU58
J 2
(-7085 2635);
DISPLAY 0.617021 (-7085 2635);
PAINT ORANGE (-7085 2635);
FORCEPROP 2 LASTPIN (-7075 2725) $PN AT57
J 2
(-7085 2735);
DISPLAY 0.617021 (-7085 2735);
PAINT ORANGE (-7085 2735);
FORCEPROP 2 LASTPIN (-7075 2775) $PN AR58
J 2
(-7085 2785);
DISPLAY 0.617021 (-7085 2785);
PAINT ORANGE (-7085 2785);
FORCEPROP 2 LASTPIN (-7075 2825) $PN AR56
J 2
(-7085 2835);
DISPLAY 0.617021 (-7085 2835);
PAINT ORANGE (-7085 2835);
FORCEPROP 2 LASTPIN (-7075 2875) $PN AP57
J 2
(-7085 2885);
DISPLAY 0.617021 (-7085 2885);
PAINT ORANGE (-7085 2885);
FORCEPROP 2 LASTPIN (-7075 2925) $PN AP55
J 2
(-7085 2935);
DISPLAY 0.617021 (-7085 2935);
PAINT ORANGE (-7085 2935);
FORCEPROP 2 LASTPIN (-7075 2975) $PN AN56
J 2
(-7085 2985);
DISPLAY 0.617021 (-7085 2985);
PAINT ORANGE (-7085 2985);
FORCEPROP 2 LASTPIN (-7075 3025) $PN AN54
J 2
(-7085 3035);
DISPLAY 0.617021 (-7085 3035);
PAINT ORANGE (-7085 3035);
FORCEPROP 2 LASTPIN (-7075 3075) $PN AN32
J 2
(-7085 3085);
DISPLAY 0.617021 (-7085 3085);
PAINT ORANGE (-7085 3085);
FORCEPROP 2 LASTPIN (-7075 3125) $PN AM55
J 2
(-7085 3135);
DISPLAY 0.617021 (-7085 3135);
PAINT ORANGE (-7085 3135);
FORCEPROP 2 LASTPIN (-7075 3175) $PN AM53
J 2
(-7085 3185);
DISPLAY 0.617021 (-7085 3185);
PAINT ORANGE (-7085 3185);
FORCEPROP 2 LASTPIN (-7075 3225) $PN AM33
J 2
(-7085 3235);
DISPLAY 0.617021 (-7085 3235);
PAINT ORANGE (-7085 3235);
FORCEPROP 2 LASTPIN (-7075 3275) $PN AL54
J 2
(-7085 3285);
DISPLAY 0.617021 (-7085 3285);
PAINT ORANGE (-7085 3285);
FORCEPROP 2 LASTPIN (-7075 3325) $PN AL52
J 2
(-7085 3335);
DISPLAY 0.617021 (-7085 3335);
PAINT ORANGE (-7085 3335);
FORCEPROP 2 LASTPIN (-7075 3375) $PN AL50
J 2
(-7085 3385);
DISPLAY 0.617021 (-7085 3385);
PAINT ORANGE (-7085 3385);
FORCEPROP 2 LASTPIN (-7075 3425) $PN AL48
J 2
(-7085 3435);
DISPLAY 0.617021 (-7085 3435);
PAINT ORANGE (-7085 3435);
FORCEPROP 2 LASTPIN (-7075 3475) $PN AL46
J 2
(-7085 3485);
DISPLAY 0.617021 (-7085 3485);
PAINT ORANGE (-7085 3485);
FORCEPROP 2 LASTPIN (-7075 3525) $PN AL34
J 2
(-7085 3535);
DISPLAY 0.617021 (-7085 3535);
PAINT ORANGE (-7085 3535);
FORCEPROP 2 LASTPIN (-7075 3575) $PN AK53
J 2
(-7085 3585);
DISPLAY 0.617021 (-7085 3585);
PAINT ORANGE (-7085 3585);
FORCEPROP 2 LASTPIN (-7075 3625) $PN AK51
J 2
(-7085 3635);
DISPLAY 0.617021 (-7085 3635);
PAINT ORANGE (-7085 3635);
FORCEPROP 2 LASTPIN (-7075 3675) $PN AK49
J 2
(-7085 3685);
DISPLAY 0.617021 (-7085 3685);
PAINT ORANGE (-7085 3685);
FORCEPROP 2 LASTPIN (-7075 3725) $PN AK47
J 2
(-7085 3735);
DISPLAY 0.617021 (-7085 3735);
PAINT ORANGE (-7085 3735);
FORCEPROP 2 LASTPIN (-7075 3775) $PN AK45
J 2
(-7085 3785);
DISPLAY 0.617021 (-7085 3785);
PAINT ORANGE (-7085 3785);
FORCEPROP 2 LASTPIN (-7075 3825) $PN AK35
J 2
(-7085 3835);
DISPLAY 0.617021 (-7085 3835);
PAINT ORANGE (-7085 3835);
FORCEPROP 2 LASTPIN (-7075 3875) $PN AJ36
J 2
(-7085 3885);
DISPLAY 0.617021 (-7085 3885);
PAINT ORANGE (-7085 3885);
FORCEPROP 2 LASTPIN (-7075 3925) $PN AH41
J 2
(-7085 3935);
DISPLAY 0.617021 (-7085 3935);
PAINT ORANGE (-7085 3935);
FORCEPROP 2 LASTPIN (-7075 3975) $PN AH39
J 2
(-7085 3985);
DISPLAY 0.617021 (-7085 3985);
PAINT ORANGE (-7085 3985);
FORCEPROP 2 LASTPIN (-7075 4025) $PN AH37
J 2
(-7085 4035);
DISPLAY 0.617021 (-7085 4035);
PAINT ORANGE (-7085 4035);
FORCEPROP 2 LASTPIN (-5675 825) $PN BN78
J 0
(-5665 835);
DISPLAY 0.617021 (-5665 835);
PAINT ORANGE (-5665 835);
FORCEPROP 2 LASTPIN (-5675 875) $PN BN76
J 0
(-5665 885);
DISPLAY 0.617021 (-5665 885);
PAINT ORANGE (-5665 885);
FORCEPROP 2 LASTPIN (-5675 925) $PN BN74
J 0
(-5665 935);
DISPLAY 0.617021 (-5665 935);
PAINT ORANGE (-5665 935);
FORCEPROP 2 LASTPIN (-5675 975) $PN BN72
J 0
(-5665 985);
DISPLAY 0.617021 (-5665 985);
PAINT ORANGE (-5665 985);
FORCEPROP 2 LASTPIN (-5675 1025) $PN BN70
J 0
(-5665 1035);
DISPLAY 0.617021 (-5665 1035);
PAINT ORANGE (-5665 1035);
FORCEPROP 2 LASTPIN (-5675 1075) $PN BN68
J 0
(-5665 1085);
DISPLAY 0.617021 (-5665 1085);
PAINT ORANGE (-5665 1085);
FORCEPROP 2 LASTPIN (-5675 1125) $PN BN66
J 0
(-5665 1135);
DISPLAY 0.617021 (-5665 1135);
PAINT ORANGE (-5665 1135);
FORCEPROP 2 LASTPIN (-5675 1175) $PN BN64
J 0
(-5665 1185);
DISPLAY 0.617021 (-5665 1185);
PAINT ORANGE (-5665 1185);
FORCEPROP 2 LASTPIN (-5675 1225) $PN BN62
J 0
(-5665 1235);
DISPLAY 0.617021 (-5665 1235);
PAINT ORANGE (-5665 1235);
FORCEPROP 2 LASTPIN (-5675 1275) $PN BN60
J 0
(-5665 1285);
DISPLAY 0.617021 (-5665 1285);
PAINT ORANGE (-5665 1285);
FORCEPROP 2 LASTPIN (-5675 1325) $PN BM83
J 0
(-5665 1335);
DISPLAY 0.617021 (-5665 1335);
PAINT ORANGE (-5665 1335);
FORCEPROP 2 LASTPIN (-5675 1375) $PN BM81
J 0
(-5665 1385);
DISPLAY 0.617021 (-5665 1385);
PAINT ORANGE (-5665 1385);
FORCEPROP 2 LASTPIN (-5675 1425) $PN BM79
J 0
(-5665 1435);
DISPLAY 0.617021 (-5665 1435);
PAINT ORANGE (-5665 1435);
FORCEPROP 2 LASTPIN (-5675 1475) $PN BM77
J 0
(-5665 1485);
DISPLAY 0.617021 (-5665 1485);
PAINT ORANGE (-5665 1485);
FORCEPROP 2 LASTPIN (-5675 1525) $PN BM75
J 0
(-5665 1535);
DISPLAY 0.617021 (-5665 1535);
PAINT ORANGE (-5665 1535);
FORCEPROP 2 LASTPIN (-5675 1575) $PN BM73
J 0
(-5665 1585);
DISPLAY 0.617021 (-5665 1585);
PAINT ORANGE (-5665 1585);
FORCEPROP 2 LASTPIN (-5675 1625) $PN BM71
J 0
(-5665 1635);
DISPLAY 0.617021 (-5665 1635);
PAINT ORANGE (-5665 1635);
FORCEPROP 2 LASTPIN (-5675 1675) $PN BM69
J 0
(-5665 1685);
DISPLAY 0.617021 (-5665 1685);
PAINT ORANGE (-5665 1685);
FORCEPROP 2 LASTPIN (-5675 1725) $PN BM67
J 0
(-5665 1735);
DISPLAY 0.617021 (-5665 1735);
PAINT ORANGE (-5665 1735);
FORCEPROP 2 LASTPIN (-5675 1775) $PN BM65
J 0
(-5665 1785);
DISPLAY 0.617021 (-5665 1785);
PAINT ORANGE (-5665 1785);
FORCEPROP 2 LASTPIN (-5675 1825) $PN BM63
J 0
(-5665 1835);
DISPLAY 0.617021 (-5665 1835);
PAINT ORANGE (-5665 1835);
FORCEPROP 2 LASTPIN (-5675 1875) $PN BM61
J 0
(-5665 1885);
DISPLAY 0.617021 (-5665 1885);
PAINT ORANGE (-5665 1885);
FORCEPROP 2 LASTPIN (-5675 1925) $PN BL84
J 0
(-5665 1935);
DISPLAY 0.617021 (-5665 1935);
PAINT ORANGE (-5665 1935);
FORCEPROP 2 LASTPIN (-5675 1975) $PN BL62
J 0
(-5665 1985);
DISPLAY 0.617021 (-5665 1985);
PAINT ORANGE (-5665 1985);
FORCEPROP 2 LASTPIN (-5675 2025) $PN BL60
J 0
(-5665 2035);
DISPLAY 0.617021 (-5665 2035);
PAINT ORANGE (-5665 2035);
FORCEPROP 2 LASTPIN (-5675 2075) $PN BK83
J 0
(-5665 2085);
DISPLAY 0.617021 (-5665 2085);
PAINT ORANGE (-5665 2085);
FORCEPROP 2 LASTPIN (-5675 2125) $PN BK81
J 0
(-5665 2135);
DISPLAY 0.617021 (-5665 2135);
PAINT ORANGE (-5665 2135);
FORCEPROP 2 LASTPIN (-5675 2175) $PN BK79
J 0
(-5665 2185);
DISPLAY 0.617021 (-5665 2185);
PAINT ORANGE (-5665 2185);
FORCEPROP 2 LASTPIN (-5675 2225) $PN BK77
J 0
(-5665 2235);
DISPLAY 0.617021 (-5665 2235);
PAINT ORANGE (-5665 2235);
FORCEPROP 2 LASTPIN (-5675 2275) $PN BK75
J 0
(-5665 2285);
DISPLAY 0.617021 (-5665 2285);
PAINT ORANGE (-5665 2285);
FORCEPROP 2 LASTPIN (-5675 2325) $PN BK73
J 0
(-5665 2335);
DISPLAY 0.617021 (-5665 2335);
PAINT ORANGE (-5665 2335);
FORCEPROP 2 LASTPIN (-5675 2375) $PN BK71
J 0
(-5665 2385);
DISPLAY 0.617021 (-5665 2385);
PAINT ORANGE (-5665 2385);
FORCEPROP 2 LASTPIN (-5675 2425) $PN BK69
J 0
(-5665 2435);
DISPLAY 0.617021 (-5665 2435);
PAINT ORANGE (-5665 2435);
FORCEPROP 2 LASTPIN (-5675 2475) $PN BK67
J 0
(-5665 2485);
DISPLAY 0.617021 (-5665 2485);
PAINT ORANGE (-5665 2485);
FORCEPROP 2 LASTPIN (-5675 2525) $PN BK65
J 0
(-5665 2535);
DISPLAY 0.617021 (-5665 2535);
PAINT ORANGE (-5665 2535);
FORCEPROP 2 LASTPIN (-5675 2575) $PN BK63
J 0
(-5665 2585);
DISPLAY 0.617021 (-5665 2585);
PAINT ORANGE (-5665 2585);
FORCEPROP 2 LASTPIN (-5675 2625) $PN BK61
J 0
(-5665 2635);
DISPLAY 0.617021 (-5665 2635);
PAINT ORANGE (-5665 2635);
FORCEPROP 2 LASTPIN (-5675 2675) $PN BJ84
J 0
(-5665 2685);
DISPLAY 0.617021 (-5665 2685);
PAINT ORANGE (-5665 2685);
FORCEPROP 2 LASTPIN (-5675 2725) $PN BJ82
J 0
(-5665 2735);
DISPLAY 0.617021 (-5665 2735);
PAINT ORANGE (-5665 2735);
FORCEPROP 2 LASTPIN (-5675 2775) $PN BJ80
J 0
(-5665 2785);
DISPLAY 0.617021 (-5665 2785);
PAINT ORANGE (-5665 2785);
FORCEPROP 2 LASTPIN (-5675 2825) $PN BJ78
J 0
(-5665 2835);
DISPLAY 0.617021 (-5665 2835);
PAINT ORANGE (-5665 2835);
FORCEPROP 2 LASTPIN (-5675 2875) $PN BJ76
J 0
(-5665 2885);
DISPLAY 0.617021 (-5665 2885);
PAINT ORANGE (-5665 2885);
FORCEPROP 2 LASTPIN (-5675 2925) $PN BJ74
J 0
(-5665 2935);
DISPLAY 0.617021 (-5665 2935);
PAINT ORANGE (-5665 2935);
FORCEPROP 2 LASTPIN (-5675 2975) $PN BJ72
J 0
(-5665 2985);
DISPLAY 0.617021 (-5665 2985);
PAINT ORANGE (-5665 2985);
FORCEPROP 2 LASTPIN (-5675 3025) $PN BJ70
J 0
(-5665 3035);
DISPLAY 0.617021 (-5665 3035);
PAINT ORANGE (-5665 3035);
FORCEPROP 2 LASTPIN (-5675 3075) $PN BJ68
J 0
(-5665 3085);
DISPLAY 0.617021 (-5665 3085);
PAINT ORANGE (-5665 3085);
FORCEPROP 2 LASTPIN (-5675 3125) $PN BJ66
J 0
(-5665 3135);
DISPLAY 0.617021 (-5665 3135);
PAINT ORANGE (-5665 3135);
FORCEPROP 2 LASTPIN (-5675 3175) $PN BJ64
J 0
(-5665 3185);
DISPLAY 0.617021 (-5665 3185);
PAINT ORANGE (-5665 3185);
FORCEPROP 2 LASTPIN (-5675 3225) $PN BJ62
J 0
(-5665 3235);
DISPLAY 0.617021 (-5665 3235);
PAINT ORANGE (-5665 3235);
FORCEPROP 2 LASTPIN (-5675 3275) $PN BJ60
J 0
(-5665 3285);
DISPLAY 0.617021 (-5665 3285);
PAINT ORANGE (-5665 3285);
FORCEPROP 2 LASTPIN (-5675 3325) $PN BH83
J 0
(-5665 3335);
DISPLAY 0.617021 (-5665 3335);
PAINT ORANGE (-5665 3335);
FORCEPROP 2 LASTPIN (-5675 3375) $PN BH81
J 0
(-5665 3385);
DISPLAY 0.617021 (-5665 3385);
PAINT ORANGE (-5665 3385);
FORCEPROP 2 LASTPIN (-5675 3425) $PN BH79
J 0
(-5665 3435);
DISPLAY 0.617021 (-5665 3435);
PAINT ORANGE (-5665 3435);
FORCEPROP 2 LASTPIN (-5675 3525) $PN BH75
J 0
(-5665 3535);
DISPLAY 0.617021 (-5665 3535);
PAINT ORANGE (-5665 3535);
FORCEPROP 2 LASTPIN (-5675 3575) $PN BH73
J 0
(-5665 3585);
DISPLAY 0.617021 (-5665 3585);
PAINT ORANGE (-5665 3585);
FORCEPROP 2 LASTPIN (-5675 3625) $PN BH71
J 0
(-5665 3635);
DISPLAY 0.617021 (-5665 3635);
PAINT ORANGE (-5665 3635);
FORCEPROP 2 LASTPIN (-5675 3675) $PN BH69
J 0
(-5665 3685);
DISPLAY 0.617021 (-5665 3685);
PAINT ORANGE (-5665 3685);
FORCEPROP 2 LASTPIN (-5675 3725) $PN BH67
J 0
(-5665 3735);
DISPLAY 0.617021 (-5665 3735);
PAINT ORANGE (-5665 3735);
FORCEPROP 2 LASTPIN (-5675 3775) $PN BH65
J 0
(-5665 3785);
DISPLAY 0.617021 (-5665 3785);
PAINT ORANGE (-5665 3785);
FORCEPROP 2 LASTPIN (-5675 3825) $PN BH63
J 0
(-5665 3835);
DISPLAY 0.617021 (-5665 3835);
PAINT ORANGE (-5665 3835);
FORCEPROP 2 LASTPIN (-5675 3875) $PN BH61
J 0
(-5665 3885);
DISPLAY 0.617021 (-5665 3885);
PAINT ORANGE (-5665 3885);
FORCEPROP 2 LASTPIN (-5675 3975) $PN BG70
J 0
(-5665 3985);
DISPLAY 0.617021 (-5665 3985);
PAINT ORANGE (-5665 3985);
FORCEPROP 2 LASTPIN (-5675 4025) $PN BG68
J 0
(-5665 4035);
DISPLAY 0.617021 (-5665 4035);
PAINT ORANGE (-5665 4035);
FORCEPROP 2 LASTPIN (-5675 4075) $PN BG66
J 0
(-5665 4085);
DISPLAY 0.617021 (-5665 4085);
PAINT ORANGE (-5665 4085);
FORCEPROP 2 LASTPIN (-7075 4075) $PN AG42
J 2
(-7085 4085);
DISPLAY 0.617021 (-7085 4085);
PAINT ORANGE (-7085 4085);
FORCEPROP 2 LASTPIN (-7075 4125) $PN AG40
J 2
(-7085 4135);
DISPLAY 0.617021 (-7085 4135);
PAINT ORANGE (-7085 4135);
FORCEPROP 2 LASTPIN (-7075 4175) $PN AG38
J 2
(-7085 4185);
DISPLAY 0.617021 (-7085 4185);
PAINT ORANGE (-7085 4185);
FORCEPROP 2 LASTPIN (-7075 4225) $PN AF43
J 2
(-7085 4235);
DISPLAY 0.617021 (-7085 4235);
PAINT ORANGE (-7085 4235);
FORCEPROP 1 LAST LOCATION U2D1
J 0
(-7025 4475);
DISPLAY 0.617021 (-7025 4475);
PAINT AQUA (-7025 4475);
FORCEPROP 2 LASTPIN (-5675 4125) $PN BG64
J 0
(-5665 4135);
DISPLAY 0.617021 (-5665 4135);
PAINT ORANGE (-5665 4135);
FORCEPROP 2 LASTPIN (-5675 4175) $PN BG62
J 0
(-5665 4185);
DISPLAY 0.617021 (-5665 4185);
PAINT ORANGE (-5665 4185);
FORCEPROP 2 LASTPIN (-5675 4225) $PN BG60
J 0
(-5665 4235);
DISPLAY 0.617021 (-5665 4235);
PAINT ORANGE (-5665 4235);
FORCEPROP 2 LASTPIN (-5675 3925) $PN BG84
J 0
(-5665 3935);
DISPLAY 0.617021 (-5665 3935);
PAINT ORANGE (-5665 3935);
FORCEPROP 1 LAST MATERIAL IC
J 0
(-7025 4425);
DISPLAY 0.617021 (-7025 4425);
PAINT SKYBLUE (-7025 4425);
FORCEPROP 2 LASTPIN (-7075 2675) $PN AT59
J 2
(-7085 2685);
DISPLAY 0.617021 (-7085 2685);
PAINT ORANGE (-7085 2685);
FORCEPROP 2 LASTPIN (-5675 3475) $PN BH77
J 0
(-5665 3485);
DISPLAY 0.617021 (-5665 3485);
PAINT ORANGE (-5665 3485);
FORCEPROP 2 LAST CDS_LIB chpset_lib
J 0
(-6375 2525);
PAINT ORANGE (-6375 2525);
DISPLAY INVISIBLE (-6375 2525);
FORCEPROP 2 LAST CDS_LOCATION U2D1
J 0
(-7025 4475);
DISPLAY 0.617021 (-7025 4475);
PAINT AQUA (-7025 4475);
DISPLAY INVISIBLE (-7025 4475);
FORCEPROP 2 LAST SEC 18
J 0
(-7025 4525);
DISPLAY 0.680851 (-7025 4525);
PAINT MONO (-7025 4525);
DISPLAY INVISIBLE (-7025 4525);
FORCEPROP 2 LAST SEC_TYPE BGA1
J 0
(-7025 4525);
DISPLAY 1.021277 (-7025 4525);
PAINT ORANGE (-7025 4525);
DISPLAY INVISIBLE (-7025 4525);
FORCEPROP 1 LAST PACK_TYPE BGA1
J 0
(-7025 4525);
PAINT SKYBLUE (-7025 4525);
DISPLAY INVISIBLE (-7025 4525);
FORCEPROP 1 LAST PATH I50
J 0
(-6375 4425);
PAINT GREEN (-6375 4425);
DISPLAY INVISIBLE (-6375 4425);
FORCEADD SKX_EXT_B..19
(-2675 2525);
FORCEPROP 2 LASTPIN (-3375 825) $PN BY83
J 2
(-3385 835);
DISPLAY 0.617021 (-3385 835);
PAINT ORANGE (-3385 835);
FORCEPROP 2 LASTPIN (-3375 875) $PN BY81
J 2
(-3385 885);
DISPLAY 0.617021 (-3385 885);
PAINT ORANGE (-3385 885);
FORCEPROP 2 LASTPIN (-3375 925) $PN BY79
J 2
(-3385 935);
DISPLAY 0.617021 (-3385 935);
PAINT ORANGE (-3385 935);
FORCEPROP 2 LASTPIN (-3375 975) $PN BY77
J 2
(-3385 985);
DISPLAY 0.617021 (-3385 985);
PAINT ORANGE (-3385 985);
FORCEPROP 1 LAST PART_NUMBER TBD
J 0
(-3325 575);
DISPLAY 0.617021 (-3325 575);
PAINT BLUE (-3325 575);
FORCEPROP 2 LASTPIN (-3375 1025) $PN BY75
J 2
(-3385 1035);
DISPLAY 0.617021 (-3385 1035);
PAINT ORANGE (-3385 1035);
FORCEPROP 2 LASTPIN (-3375 1075) $PN BY73
J 2
(-3385 1085);
DISPLAY 0.617021 (-3385 1085);
PAINT ORANGE (-3385 1085);
FORCEPROP 2 LASTPIN (-3375 1125) $PN BY61
J 2
(-3385 1135);
DISPLAY 0.617021 (-3385 1135);
PAINT ORANGE (-3385 1135);
FORCEPROP 2 LASTPIN (-3375 1175) $PN BW84
J 2
(-3385 1185);
DISPLAY 0.617021 (-3385 1185);
PAINT ORANGE (-3385 1185);
FORCEPROP 2 LASTPIN (-3375 1225) $PN BW70
J 2
(-3385 1235);
DISPLAY 0.617021 (-3385 1235);
PAINT ORANGE (-3385 1235);
FORCEPROP 2 LASTPIN (-3375 1275) $PN BW68
J 2
(-3385 1285);
DISPLAY 0.617021 (-3385 1285);
PAINT ORANGE (-3385 1285);
FORCEPROP 2 LASTPIN (-3375 1325) $PN BW66
J 2
(-3385 1335);
DISPLAY 0.617021 (-3385 1335);
PAINT ORANGE (-3385 1335);
FORCEPROP 2 LASTPIN (-3375 1375) $PN BW64
J 2
(-3385 1385);
DISPLAY 0.617021 (-3385 1385);
PAINT ORANGE (-3385 1385);
FORCEPROP 2 LASTPIN (-3375 1425) $PN BW62
J 2
(-3385 1435);
DISPLAY 0.617021 (-3385 1435);
PAINT ORANGE (-3385 1435);
FORCEPROP 2 LASTPIN (-3375 1475) $PN BW60
J 2
(-3385 1485);
DISPLAY 0.617021 (-3385 1485);
PAINT ORANGE (-3385 1485);
FORCEPROP 2 LASTPIN (-3375 1525) $PN BV83
J 2
(-3385 1535);
DISPLAY 0.617021 (-3385 1535);
PAINT ORANGE (-3385 1535);
FORCEPROP 2 LASTPIN (-3375 1675) $PN BV77
J 2
(-3385 1685);
DISPLAY 0.617021 (-3385 1685);
PAINT ORANGE (-3385 1685);
FORCEPROP 2 LASTPIN (-3375 1725) $PN BV75
J 2
(-3385 1735);
DISPLAY 0.617021 (-3385 1735);
PAINT ORANGE (-3385 1735);
FORCEPROP 2 LASTPIN (-3375 1575) $PN BV81
J 2
(-3385 1585);
DISPLAY 0.617021 (-3385 1585);
PAINT ORANGE (-3385 1585);
FORCEPROP 2 LASTPIN (-3375 1625) $PN BV79
J 2
(-3385 1635);
DISPLAY 0.617021 (-3385 1635);
PAINT ORANGE (-3385 1635);
FORCEPROP 2 LASTPIN (-3375 1775) $PN BV73
J 2
(-3385 1785);
DISPLAY 0.617021 (-3385 1785);
PAINT ORANGE (-3385 1785);
FORCEPROP 2 LASTPIN (-3375 1875) $PN BV69
J 2
(-3385 1885);
DISPLAY 0.617021 (-3385 1885);
PAINT ORANGE (-3385 1885);
FORCEPROP 2 LASTPIN (-3375 1825) $PN BV71
J 2
(-3385 1835);
DISPLAY 0.617021 (-3385 1835);
PAINT ORANGE (-3385 1835);
FORCEPROP 2 LASTPIN (-3375 1925) $PN BV67
J 2
(-3385 1935);
DISPLAY 0.617021 (-3385 1935);
PAINT ORANGE (-3385 1935);
FORCEPROP 2 LASTPIN (-3375 1975) $PN BV65
J 2
(-3385 1985);
DISPLAY 0.617021 (-3385 1985);
PAINT ORANGE (-3385 1985);
FORCEPROP 2 LASTPIN (-3375 2025) $PN BV63
J 2
(-3385 2035);
DISPLAY 0.617021 (-3385 2035);
PAINT ORANGE (-3385 2035);
FORCEPROP 2 LASTPIN (-3375 2175) $PN BU82
J 2
(-3385 2185);
DISPLAY 0.617021 (-3385 2185);
PAINT ORANGE (-3385 2185);
FORCEPROP 2 LASTPIN (-3375 2225) $PN BU80
J 2
(-3385 2235);
DISPLAY 0.617021 (-3385 2235);
PAINT ORANGE (-3385 2235);
FORCEPROP 2 LASTPIN (-3375 2075) $PN BV61
J 2
(-3385 2085);
DISPLAY 0.617021 (-3385 2085);
PAINT ORANGE (-3385 2085);
FORCEPROP 2 LASTPIN (-3375 2125) $PN BU84
J 2
(-3385 2135);
DISPLAY 0.617021 (-3385 2135);
PAINT ORANGE (-3385 2135);
FORCEPROP 2 LASTPIN (-3375 2275) $PN BU78
J 2
(-3385 2285);
DISPLAY 0.617021 (-3385 2285);
PAINT ORANGE (-3385 2285);
FORCEPROP 2 LASTPIN (-3375 2375) $PN BU74
J 2
(-3385 2385);
DISPLAY 0.617021 (-3385 2385);
PAINT ORANGE (-3385 2385);
FORCEPROP 2 LASTPIN (-3375 2325) $PN BU76
J 2
(-3385 2335);
DISPLAY 0.617021 (-3385 2335);
PAINT ORANGE (-3385 2335);
FORCEPROP 2 LASTPIN (-3375 2425) $PN BU72
J 2
(-3385 2435);
DISPLAY 0.617021 (-3385 2435);
PAINT ORANGE (-3385 2435);
FORCEPROP 2 LASTPIN (-3375 2475) $PN BU70
J 2
(-3385 2485);
DISPLAY 0.617021 (-3385 2485);
PAINT ORANGE (-3385 2485);
FORCEPROP 2 LASTPIN (-3375 2525) $PN BU68
J 2
(-3385 2535);
DISPLAY 0.617021 (-3385 2535);
PAINT ORANGE (-3385 2535);
FORCEPROP 2 LASTPIN (-3375 2725) $PN BU60
J 2
(-3385 2735);
DISPLAY 0.617021 (-3385 2735);
PAINT ORANGE (-3385 2735);
FORCEPROP 2 LASTPIN (-3375 2775) $PN BT83
J 2
(-3385 2785);
DISPLAY 0.617021 (-3385 2785);
PAINT ORANGE (-3385 2785);
FORCEPROP 2 LASTPIN (-3375 2675) $PN BU62
J 2
(-3385 2685);
DISPLAY 0.617021 (-3385 2685);
PAINT ORANGE (-3385 2685);
FORCEPROP 2 LASTPIN (-3375 2575) $PN BU66
J 2
(-3385 2585);
DISPLAY 0.617021 (-3385 2585);
PAINT ORANGE (-3385 2585);
FORCEPROP 2 LASTPIN (-3375 2625) $PN BU64
J 2
(-3385 2635);
DISPLAY 0.617021 (-3385 2635);
PAINT ORANGE (-3385 2635);
FORCEPROP 2 LASTPIN (-3375 2875) $PN BT79
J 2
(-3385 2885);
DISPLAY 0.617021 (-3385 2885);
PAINT ORANGE (-3385 2885);
FORCEPROP 2 LASTPIN (-3375 2825) $PN BT81
J 2
(-3385 2835);
DISPLAY 0.617021 (-3385 2835);
PAINT ORANGE (-3385 2835);
FORCEPROP 2 LASTPIN (-3375 2925) $PN BT77
J 2
(-3385 2935);
DISPLAY 0.617021 (-3385 2935);
PAINT ORANGE (-3385 2935);
FORCEPROP 2 LASTPIN (-3375 2975) $PN BT75
J 2
(-3385 2985);
DISPLAY 0.617021 (-3385 2985);
PAINT ORANGE (-3385 2985);
FORCEPROP 2 LASTPIN (-3375 3075) $PN BT71
J 2
(-3385 3085);
DISPLAY 0.617021 (-3385 3085);
PAINT ORANGE (-3385 3085);
FORCEPROP 2 LASTPIN (-3375 3125) $PN BT69
J 2
(-3385 3135);
DISPLAY 0.617021 (-3385 3135);
PAINT ORANGE (-3385 3135);
FORCEPROP 2 LASTPIN (-3375 3175) $PN BT67
J 2
(-3385 3185);
DISPLAY 0.617021 (-3385 3185);
PAINT ORANGE (-3385 3185);
FORCEPROP 2 LASTPIN (-3375 3225) $PN BT65
J 2
(-3385 3235);
DISPLAY 0.617021 (-3385 3235);
PAINT ORANGE (-3385 3235);
FORCEPROP 2 LASTPIN (-3375 3275) $PN BT63
J 2
(-3385 3285);
DISPLAY 0.617021 (-3385 3285);
PAINT ORANGE (-3385 3285);
FORCEPROP 2 LASTPIN (-3375 3325) $PN BT61
J 2
(-3385 3335);
DISPLAY 0.617021 (-3385 3335);
PAINT ORANGE (-3385 3335);
FORCEPROP 2 LASTPIN (-3375 3375) $PN BR84
J 2
(-3385 3385);
DISPLAY 0.617021 (-3385 3385);
PAINT ORANGE (-3385 3385);
FORCEPROP 2 LASTPIN (-3375 3425) $PN BR62
J 2
(-3385 3435);
DISPLAY 0.617021 (-3385 3435);
PAINT ORANGE (-3385 3435);
FORCEPROP 2 LASTPIN (-3375 3475) $PN BR60
J 2
(-3385 3485);
DISPLAY 0.617021 (-3385 3485);
PAINT ORANGE (-3385 3485);
FORCEPROP 2 LASTPIN (-3375 3525) $PN BP83
J 2
(-3385 3535);
DISPLAY 0.617021 (-3385 3535);
PAINT ORANGE (-3385 3535);
FORCEPROP 2 LASTPIN (-3375 3725) $PN BP75
J 2
(-3385 3735);
DISPLAY 0.617021 (-3385 3735);
PAINT ORANGE (-3385 3735);
FORCEPROP 2 LASTPIN (-3375 3775) $PN BP73
J 2
(-3385 3785);
DISPLAY 0.617021 (-3385 3785);
PAINT ORANGE (-3385 3785);
FORCEPROP 2 LASTPIN (-3375 3675) $PN BP77
J 2
(-3385 3685);
DISPLAY 0.617021 (-3385 3685);
PAINT ORANGE (-3385 3685);
FORCEPROP 2 LASTPIN (-3375 3575) $PN BP81
J 2
(-3385 3585);
DISPLAY 0.617021 (-3385 3585);
PAINT ORANGE (-3385 3585);
FORCEPROP 2 LASTPIN (-3375 3625) $PN BP79
J 2
(-3385 3635);
DISPLAY 0.617021 (-3385 3635);
PAINT ORANGE (-3385 3635);
FORCEPROP 2 LASTPIN (-3375 3825) $PN BP71
J 2
(-3385 3835);
DISPLAY 0.617021 (-3385 3835);
PAINT ORANGE (-3385 3835);
FORCEPROP 2 LASTPIN (-3375 3875) $PN BP69
J 2
(-3385 3885);
DISPLAY 0.617021 (-3385 3885);
PAINT ORANGE (-3385 3885);
FORCEPROP 2 LASTPIN (-3375 3925) $PN BP67
J 2
(-3385 3935);
DISPLAY 0.617021 (-3385 3935);
PAINT ORANGE (-3385 3935);
FORCEPROP 2 LASTPIN (-3375 3975) $PN BP65
J 2
(-3385 3985);
DISPLAY 0.617021 (-3385 3985);
PAINT ORANGE (-3385 3985);
FORCEPROP 2 LASTPIN (-3375 4025) $PN BP63
J 2
(-3385 4035);
DISPLAY 0.617021 (-3385 4035);
PAINT ORANGE (-3385 4035);
FORCEPROP 2 LASTPIN (-1975 825) $PN BA86
J 0
(-1965 835);
DISPLAY 0.617021 (-1965 835);
PAINT ORANGE (-1965 835);
FORCEPROP 2 LASTPIN (-1975 925) $PN AD41
J 0
(-1965 935);
DISPLAY 0.617021 (-1965 935);
PAINT ORANGE (-1965 935);
FORCEPROP 2 LASTPIN (-1975 775) $PN AY85
J 0
(-1965 785);
DISPLAY 0.617021 (-1965 785);
PAINT ORANGE (-1965 785);
FORCEPROP 2 LASTPIN (-1975 1225) $PN CY49
J 0
(-1965 1235);
DISPLAY 0.617021 (-1965 1235);
PAINT ORANGE (-1965 1235);
FORCEPROP 2 LASTPIN (-1975 1025) $PN AW86
J 0
(-1965 1035);
DISPLAY 0.617021 (-1965 1035);
PAINT ORANGE (-1965 1035);
FORCEPROP 2 LASTPIN (-1975 1125) $PN AV85
J 0
(-1965 1135);
DISPLAY 0.617021 (-1965 1135);
PAINT ORANGE (-1965 1135);
FORCEPROP 2 LASTPIN (-1975 1475) $PN CV51
J 0
(-1965 1485);
DISPLAY 0.617021 (-1965 1485);
PAINT ORANGE (-1965 1485);
FORCEPROP 2 LASTPIN (-1975 1425) $PN CW46
J 0
(-1965 1435);
DISPLAY 0.617021 (-1965 1435);
PAINT ORANGE (-1965 1435);
FORCEPROP 2 LASTPIN (-1975 1375) $PN CW48
J 0
(-1965 1385);
DISPLAY 0.617021 (-1965 1385);
PAINT ORANGE (-1965 1385);
FORCEPROP 2 LASTPIN (-1975 1325) $PN CW50
J 0
(-1965 1335);
DISPLAY 0.617021 (-1965 1335);
PAINT ORANGE (-1965 1335);
FORCEPROP 2 LASTPIN (-1975 1275) $PN CY47
J 0
(-1965 1285);
DISPLAY 0.617021 (-1965 1285);
PAINT ORANGE (-1965 1285);
FORCEPROP 2 LASTPIN (-1975 1525) $PN CU54
J 0
(-1965 1535);
DISPLAY 0.617021 (-1965 1535);
PAINT ORANGE (-1965 1535);
FORCEPROP 2 LASTPIN (-1975 1725) $PN CU38
J 0
(-1965 1735);
DISPLAY 0.617021 (-1965 1735);
PAINT ORANGE (-1965 1735);
FORCEPROP 2 LASTPIN (-1975 1675) $PN CU40
J 0
(-1965 1685);
DISPLAY 0.617021 (-1965 1685);
PAINT ORANGE (-1965 1685);
FORCEPROP 2 LASTPIN (-1975 1625) $PN CU42
J 0
(-1965 1635);
DISPLAY 0.617021 (-1965 1635);
PAINT ORANGE (-1965 1635);
FORCEPROP 2 LASTPIN (-1975 1575) $PN CU52
J 0
(-1965 1585);
DISPLAY 0.617021 (-1965 1585);
PAINT ORANGE (-1965 1585);
FORCEPROP 2 LASTPIN (-1975 1775) $PN CT55
J 0
(-1965 1785);
DISPLAY 0.617021 (-1965 1785);
PAINT ORANGE (-1965 1785);
FORCEPROP 2 LASTPIN (-1975 1975) $PN CT37
J 0
(-1965 1985);
DISPLAY 0.617021 (-1965 1985);
PAINT ORANGE (-1965 1985);
FORCEPROP 2 LASTPIN (-1975 1925) $PN CT39
J 0
(-1965 1935);
DISPLAY 0.617021 (-1965 1935);
PAINT ORANGE (-1965 1935);
FORCEPROP 2 LASTPIN (-1975 1875) $PN CT41
J 0
(-1965 1885);
DISPLAY 0.617021 (-1965 1885);
PAINT ORANGE (-1965 1885);
FORCEPROP 2 LASTPIN (-1975 1825) $PN CT53
J 0
(-1965 1835);
DISPLAY 0.617021 (-1965 1835);
PAINT ORANGE (-1965 1835);
FORCEPROP 2 LASTPIN (-1975 2025) $PN CR56
J 0
(-1965 2035);
DISPLAY 0.617021 (-1965 2035);
PAINT ORANGE (-1965 2035);
FORCEPROP 2 LASTPIN (-1975 2225) $PN CP55
J 0
(-1965 2235);
DISPLAY 0.617021 (-1965 2235);
PAINT ORANGE (-1965 2235);
FORCEPROP 2 LASTPIN (-1975 2175) $PN CP57
J 0
(-1965 2185);
DISPLAY 0.617021 (-1965 2185);
PAINT ORANGE (-1965 2185);
FORCEPROP 2 LASTPIN (-1975 2075) $PN CR54
J 0
(-1965 2085);
DISPLAY 0.617021 (-1965 2085);
PAINT ORANGE (-1965 2085);
FORCEPROP 2 LASTPIN (-1975 2275) $PN CP33
J 0
(-1965 2285);
DISPLAY 0.617021 (-1965 2285);
PAINT ORANGE (-1965 2285);
FORCEPROP 2 LASTPIN (-1975 2475) $PN CM57
J 0
(-1965 2485);
DISPLAY 0.617021 (-1965 2485);
PAINT ORANGE (-1965 2485);
FORCEPROP 2 LASTPIN (-1975 2425) $PN CM59
J 0
(-1965 2435);
DISPLAY 0.617021 (-1965 2435);
PAINT ORANGE (-1965 2435);
FORCEPROP 2 LASTPIN (-1975 2375) $PN CN56
J 0
(-1965 2385);
DISPLAY 0.617021 (-1965 2385);
PAINT ORANGE (-1965 2385);
FORCEPROP 2 LASTPIN (-1975 2325) $PN CN58
J 0
(-1965 2335);
DISPLAY 0.617021 (-1965 2335);
PAINT ORANGE (-1965 2335);
FORCEPROP 2 LASTPIN (-1975 2525) $PN CL60
J 0
(-1965 2535);
DISPLAY 0.617021 (-1965 2535);
PAINT ORANGE (-1965 2535);
FORCEPROP 2 LASTPIN (-1975 2775) $PN CH85
J 0
(-1965 2785);
DISPLAY 0.617021 (-1965 2785);
PAINT ORANGE (-1965 2785);
FORCEPROP 2 LASTPIN (-1975 2725) $PN CJ60
J 0
(-1965 2735);
DISPLAY 0.617021 (-1965 2735);
PAINT ORANGE (-1965 2735);
FORCEPROP 2 LASTPIN (-1975 2675) $PN CK59
J 0
(-1965 2685);
DISPLAY 0.617021 (-1965 2685);
PAINT ORANGE (-1965 2685);
FORCEPROP 2 LASTPIN (-1975 2625) $PN CK61
J 0
(-1965 2635);
DISPLAY 0.617021 (-1965 2635);
PAINT ORANGE (-1965 2635);
FORCEPROP 2 LASTPIN (-1975 3025) $PN CF61
J 0
(-1965 3035);
DISPLAY 0.617021 (-1965 3035);
PAINT ORANGE (-1965 3035);
FORCEPROP 2 LASTPIN (-1975 2975) $PN CF85
J 0
(-1965 2985);
DISPLAY 0.617021 (-1965 2985);
PAINT ORANGE (-1965 2985);
FORCEPROP 2 LASTPIN (-1975 2925) $PN CG60
J 0
(-1965 2935);
DISPLAY 0.617021 (-1965 2935);
PAINT ORANGE (-1965 2935);
FORCEPROP 2 LASTPIN (-1975 2875) $PN CG84
J 0
(-1965 2885);
DISPLAY 0.617021 (-1965 2885);
PAINT ORANGE (-1965 2885);
FORCEPROP 2 LASTPIN (-1975 2825) $PN CH61
J 0
(-1965 2835);
DISPLAY 0.617021 (-1965 2835);
PAINT ORANGE (-1965 2835);
FORCEPROP 2 LASTPIN (-1975 3275) $PN CD61
J 0
(-1965 3285);
DISPLAY 0.617021 (-1965 3285);
PAINT ORANGE (-1965 3285);
FORCEPROP 2 LASTPIN (-1975 3225) $PN CD83
J 0
(-1965 3235);
DISPLAY 0.617021 (-1965 3235);
PAINT ORANGE (-1965 3235);
FORCEPROP 2 LASTPIN (-1975 3175) $PN CD85
J 0
(-1965 3185);
DISPLAY 0.617021 (-1965 3185);
PAINT ORANGE (-1965 3185);
FORCEPROP 2 LASTPIN (-1975 3125) $PN CE60
J 0
(-1965 3135);
DISPLAY 0.617021 (-1965 3135);
PAINT ORANGE (-1965 3135);
FORCEPROP 2 LASTPIN (-1975 3075) $PN CE84
J 0
(-1965 3085);
DISPLAY 0.617021 (-1965 3085);
PAINT ORANGE (-1965 3085);
FORCEPROP 2 LASTPIN (-1975 3525) $PN CB81
J 0
(-1965 3535);
DISPLAY 0.617021 (-1965 3535);
PAINT ORANGE (-1965 3535);
FORCEPROP 2 LASTPIN (-1975 3475) $PN CB83
J 0
(-1965 3485);
DISPLAY 0.617021 (-1965 3485);
PAINT ORANGE (-1965 3485);
FORCEPROP 2 LASTPIN (-1975 3425) $PN CC60
J 0
(-1965 3435);
DISPLAY 0.617021 (-1965 3435);
PAINT ORANGE (-1965 3435);
FORCEPROP 2 LASTPIN (-1975 3375) $PN CC62
J 0
(-1965 3385);
DISPLAY 0.617021 (-1965 3385);
PAINT ORANGE (-1965 3385);
FORCEPROP 2 LASTPIN (-1975 3325) $PN CC84
J 0
(-1965 3335);
DISPLAY 0.617021 (-1965 3335);
PAINT ORANGE (-1965 3335);
FORCEPROP 2 LASTPIN (-1975 3775) $PN CB61
J 0
(-1965 3785);
DISPLAY 0.617021 (-1965 3785);
PAINT ORANGE (-1965 3785);
FORCEPROP 2 LASTPIN (-1975 3725) $PN CB73
J 0
(-1965 3735);
DISPLAY 0.617021 (-1965 3735);
PAINT ORANGE (-1965 3735);
FORCEPROP 2 LASTPIN (-1975 3675) $PN CB75
J 0
(-1965 3685);
DISPLAY 0.617021 (-1965 3685);
PAINT ORANGE (-1965 3685);
FORCEPROP 2 LASTPIN (-1975 3625) $PN CB77
J 0
(-1965 3635);
DISPLAY 0.617021 (-1965 3635);
PAINT ORANGE (-1965 3635);
FORCEPROP 2 LASTPIN (-1975 3575) $PN CB79
J 0
(-1965 3585);
DISPLAY 0.617021 (-1965 3585);
PAINT ORANGE (-1965 3585);
FORCEPROP 2 LASTPIN (-1975 3825) $PN CA84
J 0
(-1965 3835);
DISPLAY 0.617021 (-1965 3835);
PAINT ORANGE (-1965 3835);
FORCEPROP 2 LASTPIN (-1975 4025) $PN CA76
J 0
(-1965 4035);
DISPLAY 0.617021 (-1965 4035);
PAINT ORANGE (-1965 4035);
FORCEPROP 2 LASTPIN (-1975 3975) $PN CA78
J 0
(-1965 3985);
DISPLAY 0.617021 (-1965 3985);
PAINT ORANGE (-1965 3985);
FORCEPROP 2 LASTPIN (-1975 3925) $PN CA80
J 0
(-1965 3935);
DISPLAY 0.617021 (-1965 3935);
PAINT ORANGE (-1965 3935);
FORCEPROP 2 LASTPIN (-1975 3875) $PN CA82
J 0
(-1965 3885);
DISPLAY 0.617021 (-1965 3885);
PAINT ORANGE (-1965 3885);
FORCEPROP 2 LASTPIN (-1975 4075) $PN CA74
J 0
(-1965 4085);
DISPLAY 0.617021 (-1965 4085);
PAINT ORANGE (-1965 4085);
FORCEPROP 2 LASTPIN (-3375 4075) $PN BP61
J 2
(-3385 4085);
DISPLAY 0.617021 (-3385 4085);
PAINT ORANGE (-3385 4085);
FORCEPROP 2 LASTPIN (-3375 4125) $PN BN84
J 2
(-3385 4135);
DISPLAY 0.617021 (-3385 4135);
PAINT ORANGE (-3385 4135);
FORCEPROP 2 LASTPIN (-3375 4175) $PN BN82
J 2
(-3385 4185);
DISPLAY 0.617021 (-3385 4185);
PAINT ORANGE (-3385 4185);
FORCEPROP 2 LASTPIN (-3375 4225) $PN BN80
J 2
(-3385 4235);
DISPLAY 0.617021 (-3385 4235);
PAINT ORANGE (-3385 4235);
FORCEPROP 1 LAST MATERIAL IC
J 0
(-3325 4425);
DISPLAY 0.617021 (-3325 4425);
PAINT SKYBLUE (-3325 4425);
FORCEPROP 1 LAST LOCATION U2D1
J 0
(-3325 4475);
DISPLAY 0.617021 (-3325 4475);
PAINT AQUA (-3325 4475);
FORCEPROP 2 LASTPIN (-1975 4125) $PN CA72
J 0
(-1965 4135);
DISPLAY 0.617021 (-1965 4135);
PAINT ORANGE (-1965 4135);
FORCEPROP 2 LASTPIN (-1975 4175) $PN CA62
J 0
(-1965 4185);
DISPLAY 0.617021 (-1965 4185);
PAINT ORANGE (-1965 4185);
FORCEPROP 2 LASTPIN (-1975 4225) $PN CA60
J 0
(-1965 4235);
DISPLAY 0.617021 (-1965 4235);
PAINT ORANGE (-1965 4235);
FORCEPROP 2 LASTPIN (-1975 2125) $PN CR34
J 0
(-1965 2135);
DISPLAY 0.617021 (-1965 2135);
PAINT ORANGE (-1965 2135);
FORCEPROP 2 LASTPIN (-3375 3025) $PN BT73
J 2
(-3385 3035);
DISPLAY 0.617021 (-3385 3035);
PAINT ORANGE (-3385 3035);
FORCEPROP 2 LASTPIN (-1975 2575) $PN CL58
J 0
(-1965 2585);
DISPLAY 0.617021 (-1965 2585);
PAINT ORANGE (-1965 2585);
FORCEPROP 2 LAST CDS_LIB chpset_lib
J 0
(-2675 2525);
PAINT ORANGE (-2675 2525);
DISPLAY INVISIBLE (-2675 2525);
FORCEPROP 2 LAST CDS_LOCATION U2D1
J 0
(-3325 4475);
DISPLAY 0.617021 (-3325 4475);
PAINT AQUA (-3325 4475);
DISPLAY INVISIBLE (-3325 4475);
FORCEPROP 2 LAST SEC 19
J 0
(-3325 4525);
DISPLAY 0.680851 (-3325 4525);
PAINT MONO (-3325 4525);
DISPLAY INVISIBLE (-3325 4525);
FORCEPROP 2 LAST SEC_TYPE BGA1
J 0
(-3325 4525);
DISPLAY 1.021277 (-3325 4525);
PAINT ORANGE (-3325 4525);
DISPLAY INVISIBLE (-3325 4525);
FORCEPROP 1 LAST PACK_TYPE BGA1
J 0
(-3325 4525);
PAINT SKYBLUE (-3325 4525);
DISPLAY INVISIBLE (-3325 4525);
FORCEPROP 1 LAST PATH I51
J 0
(-2675 4425);
PAINT GREEN (-2675 4425);
DISPLAY INVISIBLE (-2675 4425);
FORCEADD PVCCIO_CPU1..1
(-500 1500);
FORCEPROP 3 LASTPIN (-500 1450) SIG_NAME PVCCIO_CPU1\g
J 0
(-490 1460);
DISPLAY 0.659574 (-490 1460);
PAINT MONO (-490 1460);
DISPLAY INVISIBLE (-490 1460);
FORCEPROP 1 LAST BODY_TYPE PLUMBING
J 0
(-545 1457);
DISPLAY 0.340426 (-545 1457);
PAINT GREEN (-545 1457);
DISPLAY INVISIBLE (-545 1457);
FORCEPROP 1 LAST VOLTAGE 1.1V
J 0
(-545 1457);
DISPLAY 0.340426 (-545 1457);
PAINT SKYBLUE (-545 1457);
DISPLAY INVISIBLE (-545 1457);
FORCEPROP 1 LAST PATH I52
J 0
(-450 1525);
DISPLAY 0.872340 (-450 1525);
PAINT AQUA (-450 1525);
DISPLAY INVISIBLE (-450 1525);
FORCEPROP 2 LAST CDS_LIB mstr_symbols
J 0
(-500 1500);
PAINT ORANGE (-500 1500);
DISPLAY INVISIBLE (-500 1500);
FORCEPROP 1 LAST HDL_POWER PVCCIO_CPU1
J 1
(-500 1550);
DISPLAY 0.872340 (-500 1550);
PAINT GREEN (-500 1550);
DISPLAY INVISIBLE (-500 1550);
FORCEADD RES..2
(-500 1200);
FORCEPROP 1 LASTPIN (-500 1100) $PN 2
J 0
(-495 1110);
DISPLAY 0.617021 (-495 1110);
PAINT ORANGE (-495 1110);
FORCEPROP 1 LAST TOLERANCE 1%
J 0
(-455 1225);
DISPLAY 0.617021 (-455 1225);
PAINT SKYBLUE (-455 1225);
FORCEPROP 1 LAST WATTAGE 1/16W
J 0
(-460 1175);
DISPLAY 0.617021 (-460 1175);
PAINT SKYBLUE (-460 1175);
FORCEPROP 1 LAST PACK_TYPE 0402
J 0
(-460 1025);
DISPLAY 0.617021 (-460 1025);
PAINT SKYBLUE (-460 1025);
FORCEPROP 1 LAST MATERIAL EMPTY
J 0
(-460 1125);
DISPLAY 0.617021 (-460 1125);
PAINT RED (-460 1125);
FORCEPROP 1 LASTPIN (-500 1300) $PN 1
J 0
(-495 1262);
DISPLAY 0.617021 (-495 1262);
PAINT ORANGE (-495 1262);
FORCEPROP 1 LAST VALUE 10.0
J 0
(-455 1275);
DISPLAY 0.617021 (-455 1275);
PAINT SKYBLUE (-455 1275);
FORCEPROP 1 LAST LOCATION R3D32
J 0
(-455 1325);
DISPLAY 0.617021 (-455 1325);
PAINT AQUA (-455 1325);
FORCEPROP 1 LAST PART_NUMBER G21796-066
J 0
(-460 1075);
DISPLAY 0.617021 (-460 1075);
PAINT BLUE (-460 1075);
FORCEPROP 2 LAST CDS_LIB mstr_discrete
J 0
(-500 1200);
PAINT ORANGE (-500 1200);
DISPLAY INVISIBLE (-500 1200);
FORCEPROP 1 LAST PATH I53
J 0
(-450 1375);
DISPLAY 0.978723 (-450 1375);
PAINT WHITE (-450 1375);
DISPLAY INVISIBLE (-450 1375);
FORCEPROP 0 LAST ROOM CPU1
J 0
(-450 1425);
DISPLAY 1.021277 (-450 1425);
PAINT ORANGE (-450 1425);
DISPLAY INVISIBLE (-450 1425);
FORCEPROP 2 LAST SEC 1
J 0
(-450 1425);
DISPLAY 0.680851 (-450 1425);
PAINT MONO (-450 1425);
DISPLAY INVISIBLE (-450 1425);
FORCEPROP 2 LAST SEC_TYPE 0402
J 0
(-450 1425);
DISPLAY 1.021277 (-450 1425);
PAINT ORANGE (-450 1425);
DISPLAY INVISIBLE (-450 1425);
FORCEADD DNS..2
(-495 1195);
PAINT RED (-495 1195);
FORCEPROP 1 LAST COMMENT_BODY TRUE
R 1
J 0
(-420 970);
DISPLAY 0.872340 (-420 970);
PAINT GREEN (-420 970);
DISPLAY INVISIBLE (-420 970);
FORCEPROP 2 LAST CDS_LIB mstr_misc
J 0
(-495 1195);
PAINT ORANGE (-495 1195);
DISPLAY INVISIBLE (-495 1195);
FORCEADD PRELIM..10
(-6465 2515);
PAINT GRAY (-6465 2515);
FORCEPROP 1 LAST COMMENT_BODY TRUE
J 0
(-6465 2515);
PAINT ORANGE (-6465 2515);
DISPLAY INVISIBLE (-6465 2515);
FORCEPROP 2 LAST CDS_LIB mstr_misc
J 0
(-6465 2515);
PAINT ORANGE (-6465 2515);
DISPLAY INVISIBLE (-6465 2515);
FORCEADD DESIGN_NOTE..1
(-5175 600);
FORCEPROP 0 LAST L1 CPU SYMBOLS 1-30 ARE PRELIMINARY AND SUBJECT TO CHANGE
J 0
(-5375 475);
DISPLAY 1.021277 (-5375 475);
PAINT ORANGE (-5375 475);
FORCEPROP 1 LAST COMMENT_BODY TRUE
J 0
(-5150 700);
DISPLAY 0.978723 (-5150 700);
PAINT ORANGE (-5150 700);
DISPLAY INVISIBLE (-5150 700);
FORCEPROP 2 LAST CDS_LIB mstr_symbols
J 0
(-5175 600);
PAINT ORANGE (-5175 600);
DISPLAY INVISIBLE (-5175 600);
FORCEADD INTEL_CORP_BPAGE..1
(0 0);
FORCEPROP 1 LAST CDS_CON_LAST_MODIFIED Fri Jun 16 17:48:26 2017
J 0
(-1425 325);
DISPLAY 1.340426 (-1425 325);
PAINT GREEN (-1425 325);
DISPLAY INVISIBLE (-1425 325);
FORCEPROP 1 LAST CUSTOM_TXT_CDS <CURRENT_DESIGN_SHEET> OF <TOTAL_DESIGN_SHEETS>
J 0
(-500 25);
PAINT ORANGE (-500 25);
FORCEPROP 1 LAST CUSTOM_TXT_CDS <CON_LAST_MODIFIED>
J 0
(-4000 100);
PAINT ORANGE (-4000 100);
FORCEPROP 2 LAST CUSTOM_TXT_CDS <XR_PAGE_TITLE>
J 0
(-7890 5250);
DISPLAY 0.638298 (-7890 5250);
PAINT PINK (-7890 5250);
DISPLAY INVISIBLE (-7890 5250);
FORCEPROP 1 LAST SCH_TITLE SKYLAKE - SKT1 - 17 OF 21
J 0
(-7950 50);
DISPLAY 1.212766 (-7950 50);
PAINT GREEN (-7950 50);
FORCEPROP 2 LAST PAGE_BORDER TRUE
J 0
(-7890 5250);
DISPLAY 0.851064 (-7890 5250);
PAINT PINK (-7890 5250);
DISPLAY INVISIBLE (-7890 5250);
FORCEPROP 2 LAST CDS_LIB mstr_symbols
J 0
(0 0);
PAINT ORANGE (0 0);
DISPLAY INVISIBLE (0 0);
FORCEPROP 1 LAST COMMENT_BODY TRUE
J 0
(12 12);
DISPLAY 0.638298 (12 12);
PAINT GREEN (12 12);
DISPLAY INVISIBLE (12 12);
FORCEPROP 2 LAST CDS_XR_PAGE_TITLE CR-71 : @BASEBOARD_FAB2_LIB.BASEBOARD_FAB2(SCH_1):PAGE71
J 0
(-7890 5250);
DISPLAY 0.638298 (-7890 5250);
PAINT PINK (-7890 5250);
DISPLAY INVISIBLE (-7890 5250);
WIRE 16 -1 (-5425 4225)(-5425 4375);
WIRE 16 -1 (-5425 4175)(-5425 4225);
WIRE 16 -1 (-5425 4225)(-5675 4225);
WIRE 16 -1 (-5425 4125)(-5425 4175);
WIRE 16 -1 (-5425 4175)(-5675 4175);
WIRE 16 -1 (-5425 4125)(-5425 4075);
WIRE 16 -1 (-5425 4125)(-5675 4125);
WIRE 16 -1 (-5425 4075)(-5425 4025);
WIRE 16 -1 (-5425 4075)(-5675 4075);
WIRE 16 -1 (-5425 4025)(-5425 3975);
WIRE 16 -1 (-5425 4025)(-5675 4025);
WIRE 16 -1 (-5425 3975)(-5425 3925);
WIRE 16 -1 (-5425 3975)(-5675 3975);
WIRE 16 -1 (-5425 3925)(-5425 3875);
WIRE 16 -1 (-5425 3925)(-5675 3925);
WIRE 16 -1 (-5425 3875)(-5425 3825);
WIRE 16 -1 (-5425 3875)(-5675 3875);
WIRE 16 -1 (-5425 3825)(-5425 3775);
WIRE 16 -1 (-5425 3825)(-5675 3825);
WIRE 16 -1 (-5425 3775)(-5425 3725);
WIRE 16 -1 (-5425 3775)(-5675 3775);
WIRE 16 -1 (-5425 3725)(-5425 3675);
WIRE 16 -1 (-5425 3725)(-5675 3725);
WIRE 16 -1 (-5425 3675)(-5425 3625);
WIRE 16 -1 (-5425 3675)(-5675 3675);
WIRE 16 -1 (-5425 3625)(-5425 3575);
WIRE 16 -1 (-5425 3625)(-5675 3625);
WIRE 16 -1 (-5425 3575)(-5425 3525);
WIRE 16 -1 (-5425 3575)(-5675 3575);
WIRE 16 -1 (-5425 3525)(-5425 3475);
WIRE 16 -1 (-5425 3525)(-5675 3525);
WIRE 16 -1 (-5425 3475)(-5425 3425);
WIRE 16 -1 (-5425 3475)(-5675 3475);
WIRE 16 -1 (-5425 3425)(-5425 3375);
WIRE 16 -1 (-5425 3425)(-5675 3425);
WIRE 16 -1 (-5425 3375)(-5425 3325);
WIRE 16 -1 (-5425 3375)(-5675 3375);
WIRE 16 -1 (-5425 3325)(-5425 3275);
WIRE 16 -1 (-5425 3325)(-5675 3325);
WIRE 16 -1 (-5425 3275)(-5425 3225);
WIRE 16 -1 (-5425 3275)(-5675 3275);
WIRE 16 -1 (-5425 3225)(-5425 3175);
WIRE 16 -1 (-5425 3225)(-5675 3225);
WIRE 16 -1 (-5425 3175)(-5425 3125);
WIRE 16 -1 (-5425 3175)(-5675 3175);
WIRE 16 -1 (-5425 3125)(-5425 3075);
WIRE 16 -1 (-5425 3125)(-5675 3125);
WIRE 16 -1 (-5425 3075)(-5425 3025);
WIRE 16 -1 (-5425 3075)(-5675 3075);
WIRE 16 -1 (-5425 3025)(-5425 2975);
WIRE 16 -1 (-5425 3025)(-5675 3025);
WIRE 16 -1 (-5425 2925)(-5425 2975);
WIRE 16 -1 (-5425 2975)(-5675 2975);
WIRE 16 -1 (-5425 2875)(-5425 2925);
WIRE 16 -1 (-5425 2925)(-5675 2925);
WIRE 16 -1 (-5425 2875)(-5425 2825);
WIRE 16 -1 (-5425 2875)(-5675 2875);
WIRE 16 -1 (-5425 2825)(-5425 2775);
WIRE 16 -1 (-5425 2825)(-5675 2825);
WIRE 16 -1 (-5425 2725)(-5425 2775);
WIRE 16 -1 (-5425 2775)(-5675 2775);
WIRE 16 -1 (-5425 2675)(-5425 2725);
WIRE 16 -1 (-5425 2725)(-5675 2725);
WIRE 16 -1 (-5425 2625)(-5425 2675);
WIRE 16 -1 (-5425 2675)(-5675 2675);
WIRE 16 -1 (-5425 2575)(-5425 2625);
WIRE 16 -1 (-5425 2625)(-5675 2625);
WIRE 16 -1 (-5425 2525)(-5425 2575);
WIRE 16 -1 (-5425 2575)(-5675 2575);
WIRE 16 -1 (-5425 2525)(-5425 2475);
WIRE 16 -1 (-5425 2525)(-5675 2525);
WIRE 16 -1 (-5425 2475)(-5425 2425);
WIRE 16 -1 (-5675 2475)(-5425 2475);
WIRE 16 -1 (-5425 2425)(-5425 2375);
WIRE 16 -1 (-5425 2425)(-5675 2425);
WIRE 16 -1 (-5425 2375)(-5425 2325);
WIRE 16 -1 (-5425 2375)(-5675 2375);
WIRE 16 -1 (-5425 2275)(-5425 2325);
WIRE 16 -1 (-5675 2325)(-5425 2325);
WIRE 16 -1 (-5425 2225)(-5425 2275);
WIRE 16 -1 (-5675 2275)(-5425 2275);
WIRE 16 -1 (-5425 2175)(-5425 2225);
WIRE 16 -1 (-5675 2225)(-5425 2225);
WIRE 16 -1 (-5425 2175)(-5425 2125);
WIRE 16 -1 (-5425 2175)(-5675 2175);
WIRE 16 -1 (-5425 2125)(-5425 2075);
WIRE 16 -1 (-5425 2125)(-5675 2125);
WIRE 16 -1 (-5425 2025)(-5425 2075);
WIRE 16 -1 (-5425 2075)(-5675 2075);
WIRE 16 -1 (-5425 1975)(-5425 2025);
WIRE 16 -1 (-5425 2025)(-5675 2025);
WIRE 16 -1 (-5425 1925)(-5425 1975);
WIRE 16 -1 (-5425 1975)(-5675 1975);
WIRE 16 -1 (-5425 1875)(-5425 1925);
WIRE 16 -1 (-5425 1925)(-5675 1925);
WIRE 16 -1 (-5425 1825)(-5425 1875);
WIRE 16 -1 (-5425 1875)(-5675 1875);
WIRE 16 -1 (-5425 1825)(-5425 1775);
WIRE 16 -1 (-5425 1825)(-5675 1825);
WIRE 16 -1 (-5425 1775)(-5425 1725);
WIRE 16 -1 (-5675 1775)(-5425 1775);
WIRE 16 -1 (-5425 1725)(-5425 1675);
WIRE 16 -1 (-5425 1725)(-5675 1725);
WIRE 16 -1 (-5425 1675)(-5425 1625);
WIRE 16 -1 (-5425 1675)(-5675 1675);
WIRE 16 -1 (-5425 1575)(-5425 1625);
WIRE 16 -1 (-5675 1625)(-5425 1625);
WIRE 16 -1 (-5425 1525)(-5425 1575);
WIRE 16 -1 (-5675 1575)(-5425 1575);
WIRE 16 -1 (-5425 1475)(-5425 1525);
WIRE 16 -1 (-5675 1525)(-5425 1525);
WIRE 16 -1 (-5425 1475)(-5425 1425);
WIRE 16 -1 (-5425 1475)(-5675 1475);
WIRE 16 -1 (-5425 1425)(-5425 1375);
WIRE 16 -1 (-5425 1425)(-5675 1425);
WIRE 16 -1 (-5425 1325)(-5425 1375);
WIRE 16 -1 (-5425 1375)(-5675 1375);
WIRE 16 -1 (-5425 1275)(-5425 1325);
WIRE 16 -1 (-5425 1325)(-5675 1325);
WIRE 16 -1 (-5425 1225)(-5425 1275);
WIRE 16 -1 (-5425 1275)(-5675 1275);
WIRE 16 -1 (-5425 1175)(-5425 1225);
WIRE 16 -1 (-5425 1225)(-5675 1225);
WIRE 16 -1 (-5425 1125)(-5425 1175);
WIRE 16 -1 (-5425 1175)(-5675 1175);
WIRE 16 -1 (-5425 1125)(-5425 1075);
WIRE 16 -1 (-5425 1125)(-5675 1125);
WIRE 16 -1 (-5425 1075)(-5425 1025);
WIRE 16 -1 (-5675 1075)(-5425 1075);
WIRE 16 -1 (-5425 1025)(-5425 975);
WIRE 16 -1 (-5425 1025)(-5675 1025);
WIRE 16 -1 (-5425 975)(-5425 925);
WIRE 16 -1 (-5425 975)(-5675 975);
WIRE 16 -1 (-5425 875)(-5425 925);
WIRE 16 -1 (-5675 925)(-5425 925);
WIRE 16 -1 (-5425 825)(-5425 875);
WIRE 16 -1 (-5675 875)(-5425 875);
WIRE 16 -1 (-5675 825)(-5425 825);
WIRE 16 -1 (-7325 4350)(-7325 4225);
WIRE 16 -1 (-7325 4225)(-7325 4175);
WIRE 16 -1 (-7075 4225)(-7325 4225);
WIRE 16 -1 (-7325 4175)(-7325 4125);
WIRE 16 -1 (-7075 4175)(-7325 4175);
WIRE 16 -1 (-7325 4125)(-7325 4075);
WIRE 16 -1 (-7075 4125)(-7325 4125);
WIRE 16 -1 (-7325 4075)(-7325 4025);
WIRE 16 -1 (-7075 4075)(-7325 4075);
WIRE 16 -1 (-7325 4025)(-7325 3975);
WIRE 16 -1 (-7075 4025)(-7325 4025);
WIRE 16 -1 (-7325 3975)(-7325 3925);
WIRE 16 -1 (-7075 3975)(-7325 3975);
WIRE 16 -1 (-7325 3925)(-7325 3875);
WIRE 16 -1 (-7075 3925)(-7325 3925);
WIRE 16 -1 (-7325 3875)(-7325 3825);
WIRE 16 -1 (-7075 3875)(-7325 3875);
WIRE 16 -1 (-7325 3825)(-7325 3775);
WIRE 16 -1 (-7075 3825)(-7325 3825);
WIRE 16 -1 (-7325 3775)(-7325 3725);
WIRE 16 -1 (-7075 3775)(-7325 3775);
WIRE 16 -1 (-7325 3725)(-7325 3675);
WIRE 16 -1 (-7075 3725)(-7325 3725);
WIRE 16 -1 (-7325 3675)(-7325 3625);
WIRE 16 -1 (-7075 3675)(-7325 3675);
WIRE 16 -1 (-7325 3625)(-7325 3575);
WIRE 16 -1 (-7075 3625)(-7325 3625);
WIRE 16 -1 (-7325 3575)(-7325 3525);
WIRE 16 -1 (-7075 3575)(-7325 3575);
WIRE 16 -1 (-7325 3525)(-7325 3475);
WIRE 16 -1 (-7075 3525)(-7325 3525);
WIRE 16 -1 (-7325 3475)(-7325 3425);
WIRE 16 -1 (-7075 3475)(-7325 3475);
WIRE 16 -1 (-7325 3425)(-7325 3375);
WIRE 16 -1 (-7075 3425)(-7325 3425);
WIRE 16 -1 (-7325 3375)(-7325 3325);
WIRE 16 -1 (-7075 3375)(-7325 3375);
WIRE 16 -1 (-7325 3325)(-7325 3275);
WIRE 16 -1 (-7075 3325)(-7325 3325);
WIRE 16 -1 (-7325 3275)(-7325 3225);
WIRE 16 -1 (-7075 3275)(-7325 3275);
WIRE 16 -1 (-7325 3225)(-7325 3175);
WIRE 16 -1 (-7075 3225)(-7325 3225);
WIRE 16 -1 (-7325 3175)(-7325 3125);
WIRE 16 -1 (-7075 3175)(-7325 3175);
WIRE 16 -1 (-7325 3125)(-7325 3075);
WIRE 16 -1 (-7075 3125)(-7325 3125);
WIRE 16 -1 (-7325 3075)(-7325 3025);
WIRE 16 -1 (-7075 3075)(-7325 3075);
WIRE 16 -1 (-7325 3025)(-7325 2975);
WIRE 16 -1 (-7075 3025)(-7325 3025);
WIRE 16 -1 (-7325 2975)(-7325 2925);
WIRE 16 -1 (-7075 2975)(-7325 2975);
WIRE 16 -1 (-7325 2925)(-7325 2875);
WIRE 16 -1 (-7075 2925)(-7325 2925);
WIRE 16 -1 (-7325 2875)(-7325 2825);
WIRE 16 -1 (-7075 2875)(-7325 2875);
WIRE 16 -1 (-7325 2825)(-7325 2775);
WIRE 16 -1 (-7075 2825)(-7325 2825);
WIRE 16 -1 (-7325 2775)(-7325 2725);
WIRE 16 -1 (-7075 2775)(-7325 2775);
WIRE 16 -1 (-7325 2725)(-7325 2675);
WIRE 16 -1 (-7075 2725)(-7325 2725);
WIRE 16 -1 (-7325 2675)(-7325 2625);
WIRE 16 -1 (-7075 2675)(-7325 2675);
WIRE 16 -1 (-7325 2625)(-7325 2575);
WIRE 16 -1 (-7075 2625)(-7325 2625);
WIRE 16 -1 (-7325 2575)(-7325 2525);
WIRE 16 -1 (-7075 2575)(-7325 2575);
WIRE 16 -1 (-7325 2525)(-7325 2475);
WIRE 16 -1 (-7075 2525)(-7325 2525);
WIRE 16 -1 (-7325 2475)(-7325 2425);
WIRE 16 -1 (-7075 2475)(-7325 2475);
WIRE 16 -1 (-7325 2425)(-7325 2375);
WIRE 16 -1 (-7075 2425)(-7325 2425);
WIRE 16 -1 (-7325 2375)(-7325 2325);
WIRE 16 -1 (-7075 2375)(-7325 2375);
WIRE 16 -1 (-7325 2325)(-7325 2275);
WIRE 16 -1 (-7075 2325)(-7325 2325);
WIRE 16 -1 (-7325 2275)(-7325 2225);
WIRE 16 -1 (-7075 2275)(-7325 2275);
WIRE 16 -1 (-7325 2225)(-7325 2175);
WIRE 16 -1 (-7075 2225)(-7325 2225);
WIRE 16 -1 (-7325 2175)(-7325 2125);
WIRE 16 -1 (-7075 2175)(-7325 2175);
WIRE 16 -1 (-7325 2125)(-7325 2075);
WIRE 16 -1 (-7075 2125)(-7325 2125);
WIRE 16 -1 (-7325 2075)(-7325 2025);
WIRE 16 -1 (-7075 2075)(-7325 2075);
WIRE 16 -1 (-7325 2025)(-7325 1975);
WIRE 16 -1 (-7075 2025)(-7325 2025);
WIRE 16 -1 (-7325 1975)(-7325 1925);
WIRE 16 -1 (-7075 1975)(-7325 1975);
WIRE 16 -1 (-7325 1925)(-7325 1875);
WIRE 16 -1 (-7075 1925)(-7325 1925);
WIRE 16 -1 (-7325 1875)(-7325 1825);
WIRE 16 -1 (-7075 1875)(-7325 1875);
WIRE 16 -1 (-7325 1825)(-7325 1775);
WIRE 16 -1 (-7075 1825)(-7325 1825);
WIRE 16 -1 (-7325 1775)(-7325 1725);
WIRE 16 -1 (-7075 1775)(-7325 1775);
WIRE 16 -1 (-7325 1725)(-7325 1675);
WIRE 16 -1 (-7075 1725)(-7325 1725);
WIRE 16 -1 (-7325 1675)(-7325 1625);
WIRE 16 -1 (-7075 1675)(-7325 1675);
WIRE 16 -1 (-7325 1625)(-7325 1575);
WIRE 16 -1 (-7075 1625)(-7325 1625);
WIRE 16 -1 (-7325 1575)(-7325 1525);
WIRE 16 -1 (-7075 1575)(-7325 1575);
WIRE 16 -1 (-7325 1525)(-7325 1475);
WIRE 16 -1 (-7075 1525)(-7325 1525);
WIRE 16 -1 (-7325 1475)(-7325 1425);
WIRE 16 -1 (-7075 1475)(-7325 1475);
WIRE 16 -1 (-7325 1425)(-7325 1375);
WIRE 16 -1 (-7075 1425)(-7325 1425);
WIRE 16 -1 (-7325 1375)(-7325 1325);
WIRE 16 -1 (-7075 1375)(-7325 1375);
WIRE 16 -1 (-7325 1325)(-7325 1275);
WIRE 16 -1 (-7075 1325)(-7325 1325);
WIRE 16 -1 (-7325 1275)(-7325 1225);
WIRE 16 -1 (-7075 1275)(-7325 1275);
WIRE 16 -1 (-7325 1225)(-7325 1175);
WIRE 16 -1 (-7075 1225)(-7325 1225);
WIRE 16 -1 (-7325 1175)(-7325 1125);
WIRE 16 -1 (-7075 1175)(-7325 1175);
WIRE 16 -1 (-7325 1125)(-7325 1075);
WIRE 16 -1 (-7075 1125)(-7325 1125);
WIRE 16 -1 (-7325 1075)(-7325 1025);
WIRE 16 -1 (-7075 1075)(-7325 1075);
WIRE 16 -1 (-7325 1025)(-7325 975);
WIRE 16 -1 (-7075 1025)(-7325 1025);
WIRE 16 -1 (-7325 975)(-7325 925);
WIRE 16 -1 (-7075 975)(-7325 975);
WIRE 16 -1 (-7325 925)(-7325 875);
WIRE 16 -1 (-7075 925)(-7325 925);
WIRE 16 -1 (-7325 875)(-7325 825);
WIRE 16 -1 (-7075 875)(-7325 875);
WIRE 16 -1 (-7075 825)(-7325 825);
WIRE 16 -1 (-3600 4350)(-3600 4225);
WIRE 16 -1 (-3600 4225)(-3600 4175);
WIRE 16 -1 (-3600 4225)(-3375 4225);
WIRE 16 -1 (-3600 4175)(-3600 4125);
WIRE 16 -1 (-3600 4175)(-3375 4175);
WIRE 16 -1 (-3600 4125)(-3600 4075);
WIRE 16 -1 (-3600 4125)(-3375 4125);
WIRE 16 -1 (-3600 4075)(-3600 4025);
WIRE 16 -1 (-3600 4075)(-3375 4075);
WIRE 16 -1 (-3600 4025)(-3600 3975);
WIRE 16 -1 (-3600 4025)(-3375 4025);
WIRE 16 -1 (-3600 3975)(-3600 3925);
WIRE 16 -1 (-3600 3975)(-3375 3975);
WIRE 16 -1 (-3600 3925)(-3600 3875);
WIRE 16 -1 (-3600 3925)(-3375 3925);
WIRE 16 -1 (-3600 3875)(-3600 3825);
WIRE 16 -1 (-3600 3875)(-3375 3875);
WIRE 16 -1 (-3600 3825)(-3600 3775);
WIRE 16 -1 (-3600 3825)(-3375 3825);
WIRE 16 -1 (-3600 3775)(-3600 3725);
WIRE 16 -1 (-3600 3775)(-3375 3775);
WIRE 16 -1 (-3600 3725)(-3600 3675);
WIRE 16 -1 (-3600 3725)(-3375 3725);
WIRE 16 -1 (-3600 3675)(-3600 3625);
WIRE 16 -1 (-3600 3675)(-3375 3675);
WIRE 16 -1 (-3600 3625)(-3600 3575);
WIRE 16 -1 (-3600 3625)(-3375 3625);
WIRE 16 -1 (-3600 3575)(-3600 3525);
WIRE 16 -1 (-3600 3575)(-3375 3575);
WIRE 16 -1 (-3600 3525)(-3600 3475);
WIRE 16 -1 (-3600 3525)(-3375 3525);
WIRE 16 -1 (-3600 3475)(-3600 3425);
WIRE 16 -1 (-3600 3475)(-3375 3475);
WIRE 16 -1 (-3600 3425)(-3600 3375);
WIRE 16 -1 (-3600 3425)(-3375 3425);
WIRE 16 -1 (-3600 3375)(-3600 3325);
WIRE 16 -1 (-3600 3375)(-3375 3375);
WIRE 16 -1 (-3600 3325)(-3600 3275);
WIRE 16 -1 (-3600 3325)(-3375 3325);
WIRE 16 -1 (-3600 3275)(-3600 3225);
WIRE 16 -1 (-3600 3275)(-3375 3275);
WIRE 16 -1 (-3600 3225)(-3600 3175);
WIRE 16 -1 (-3600 3225)(-3375 3225);
WIRE 16 -1 (-3600 3175)(-3600 3125);
WIRE 16 -1 (-3600 3175)(-3375 3175);
WIRE 16 -1 (-3600 3125)(-3600 3075);
WIRE 16 -1 (-3600 3125)(-3375 3125);
WIRE 16 -1 (-3600 3075)(-3600 3025);
WIRE 16 -1 (-3600 3075)(-3375 3075);
WIRE 16 -1 (-3600 3025)(-3600 2975);
WIRE 16 -1 (-3600 3025)(-3375 3025);
WIRE 16 -1 (-3600 2975)(-3600 2925);
WIRE 16 -1 (-3600 2975)(-3375 2975);
WIRE 16 -1 (-3600 2925)(-3600 2875);
WIRE 16 -1 (-3600 2925)(-3375 2925);
WIRE 16 -1 (-3600 2875)(-3600 2825);
WIRE 16 -1 (-3600 2875)(-3375 2875);
WIRE 16 -1 (-3600 2825)(-3600 2775);
WIRE 16 -1 (-3600 2825)(-3375 2825);
WIRE 16 -1 (-3600 2775)(-3600 2725);
WIRE 16 -1 (-3600 2775)(-3375 2775);
WIRE 16 -1 (-3600 2725)(-3600 2675);
WIRE 16 -1 (-3600 2725)(-3375 2725);
WIRE 16 -1 (-3600 2675)(-3600 2625);
WIRE 16 -1 (-3600 2675)(-3375 2675);
WIRE 16 -1 (-3600 2625)(-3600 2575);
WIRE 16 -1 (-3600 2625)(-3375 2625);
WIRE 16 -1 (-3600 2575)(-3600 2525);
WIRE 16 -1 (-3600 2575)(-3375 2575);
WIRE 16 -1 (-3600 2525)(-3600 2475);
WIRE 16 -1 (-3600 2525)(-3375 2525);
WIRE 16 -1 (-3600 2475)(-3600 2425);
WIRE 16 -1 (-3600 2475)(-3375 2475);
WIRE 16 -1 (-3600 2425)(-3600 2375);
WIRE 16 -1 (-3600 2425)(-3375 2425);
WIRE 16 -1 (-3600 2375)(-3600 2325);
WIRE 16 -1 (-3600 2375)(-3375 2375);
WIRE 16 -1 (-3600 2325)(-3600 2275);
WIRE 16 -1 (-3600 2325)(-3375 2325);
WIRE 16 -1 (-3600 2275)(-3600 2225);
WIRE 16 -1 (-3600 2275)(-3375 2275);
WIRE 16 -1 (-3600 2225)(-3600 2175);
WIRE 16 -1 (-3600 2225)(-3375 2225);
WIRE 16 -1 (-3600 2175)(-3600 2125);
WIRE 16 -1 (-3600 2175)(-3375 2175);
WIRE 16 -1 (-3600 2125)(-3600 2075);
WIRE 16 -1 (-3600 2125)(-3375 2125);
WIRE 16 -1 (-3600 2075)(-3600 2025);
WIRE 16 -1 (-3600 2075)(-3375 2075);
WIRE 16 -1 (-3600 2025)(-3600 1975);
WIRE 16 -1 (-3600 2025)(-3375 2025);
WIRE 16 -1 (-3600 1975)(-3600 1925);
WIRE 16 -1 (-3600 1975)(-3375 1975);
WIRE 16 -1 (-3600 1925)(-3600 1875);
WIRE 16 -1 (-3600 1925)(-3375 1925);
WIRE 16 -1 (-3600 1875)(-3600 1825);
WIRE 16 -1 (-3600 1875)(-3375 1875);
WIRE 16 -1 (-3600 1825)(-3600 1775);
WIRE 16 -1 (-3600 1825)(-3375 1825);
WIRE 16 -1 (-3600 1775)(-3600 1725);
WIRE 16 -1 (-3600 1775)(-3375 1775);
WIRE 16 -1 (-3600 1725)(-3600 1675);
WIRE 16 -1 (-3600 1725)(-3375 1725);
WIRE 16 -1 (-3600 1675)(-3600 1625);
WIRE 16 -1 (-3600 1675)(-3375 1675);
WIRE 16 -1 (-3600 1625)(-3600 1575);
WIRE 16 -1 (-3600 1625)(-3375 1625);
WIRE 16 -1 (-3600 1575)(-3600 1525);
WIRE 16 -1 (-3600 1575)(-3375 1575);
WIRE 16 -1 (-3600 1525)(-3600 1475);
WIRE 16 -1 (-3600 1525)(-3375 1525);
WIRE 16 -1 (-3600 1475)(-3600 1425);
WIRE 16 -1 (-3600 1475)(-3375 1475);
WIRE 16 -1 (-3600 1425)(-3600 1375);
WIRE 16 -1 (-3600 1425)(-3375 1425);
WIRE 16 -1 (-3600 1375)(-3600 1325);
WIRE 16 -1 (-3600 1375)(-3375 1375);
WIRE 16 -1 (-3600 1325)(-3600 1275);
WIRE 16 -1 (-3600 1325)(-3375 1325);
WIRE 16 -1 (-3600 1275)(-3600 1225);
WIRE 16 -1 (-3600 1275)(-3375 1275);
WIRE 16 -1 (-3600 1225)(-3600 1175);
WIRE 16 -1 (-3600 1225)(-3375 1225);
WIRE 16 -1 (-3600 1175)(-3600 1125);
WIRE 16 -1 (-3600 1175)(-3375 1175);
WIRE 16 -1 (-3600 1125)(-3600 1075);
WIRE 16 -1 (-3600 1125)(-3375 1125);
WIRE 16 -1 (-3600 1075)(-3600 1025);
WIRE 16 -1 (-3600 1075)(-3375 1075);
WIRE 16 -1 (-3600 1025)(-3600 975);
WIRE 16 -1 (-3600 1025)(-3375 1025);
WIRE 16 -1 (-3600 975)(-3600 925);
WIRE 16 -1 (-3600 975)(-3375 975);
WIRE 16 -1 (-3600 925)(-3600 875);
WIRE 16 -1 (-3600 925)(-3375 925);
WIRE 16 -1 (-3600 875)(-3600 825);
WIRE 16 -1 (-3600 875)(-3375 875);
WIRE 16 -1 (-3600 825)(-3375 825);
WIRE 16 -1 (-1725 4325)(-1725 4225);
WIRE 16 -1 (-1725 4225)(-1725 4175);
WIRE 16 -1 (-1725 4225)(-1975 4225);
WIRE 16 -1 (-1725 4175)(-1725 4125);
WIRE 16 -1 (-1725 4175)(-1975 4175);
WIRE 16 -1 (-1725 4125)(-1725 4075);
WIRE 16 -1 (-1725 4125)(-1975 4125);
WIRE 16 -1 (-1725 4075)(-1725 4025);
WIRE 16 -1 (-1725 4075)(-1975 4075);
WIRE 16 -1 (-1725 4025)(-1725 3975);
WIRE 16 -1 (-1725 4025)(-1975 4025);
WIRE 16 -1 (-1725 3975)(-1725 3925);
WIRE 16 -1 (-1725 3975)(-1975 3975);
WIRE 16 -1 (-1725 3925)(-1725 3875);
WIRE 16 -1 (-1725 3925)(-1975 3925);
WIRE 16 -1 (-1725 3875)(-1725 3825);
WIRE 16 -1 (-1725 3875)(-1975 3875);
WIRE 16 -1 (-1725 3825)(-1725 3775);
WIRE 16 -1 (-1725 3825)(-1975 3825);
WIRE 16 -1 (-1725 3775)(-1725 3725);
WIRE 16 -1 (-1725 3775)(-1975 3775);
WIRE 16 -1 (-1725 3725)(-1725 3675);
WIRE 16 -1 (-1725 3725)(-1975 3725);
WIRE 16 -1 (-1725 3675)(-1725 3625);
WIRE 16 -1 (-1725 3675)(-1975 3675);
WIRE 16 -1 (-1725 3625)(-1725 3575);
WIRE 16 -1 (-1725 3625)(-1975 3625);
WIRE 16 -1 (-1725 3575)(-1725 3525);
WIRE 16 -1 (-1725 3575)(-1975 3575);
WIRE 16 -1 (-1725 3525)(-1725 3475);
WIRE 16 -1 (-1725 3525)(-1975 3525);
WIRE 16 -1 (-1725 3475)(-1725 3425);
WIRE 16 -1 (-1725 3475)(-1975 3475);
WIRE 16 -1 (-1725 3425)(-1725 3375);
WIRE 16 -1 (-1725 3425)(-1975 3425);
WIRE 16 -1 (-1725 3375)(-1725 3325);
WIRE 16 -1 (-1725 3375)(-1975 3375);
WIRE 16 -1 (-1725 3325)(-1725 3275);
WIRE 16 -1 (-1725 3325)(-1975 3325);
WIRE 16 -1 (-1725 3275)(-1725 3225);
WIRE 16 -1 (-1725 3275)(-1975 3275);
WIRE 16 -1 (-1725 3225)(-1725 3175);
WIRE 16 -1 (-1725 3225)(-1975 3225);
WIRE 16 -1 (-1725 3175)(-1725 3125);
WIRE 16 -1 (-1725 3175)(-1975 3175);
WIRE 16 -1 (-1725 3125)(-1725 3075);
WIRE 16 -1 (-1725 3125)(-1975 3125);
WIRE 16 -1 (-1725 3075)(-1725 3025);
WIRE 16 -1 (-1725 3075)(-1975 3075);
WIRE 16 -1 (-1725 3025)(-1725 2975);
WIRE 16 -1 (-1725 3025)(-1975 3025);
WIRE 16 -1 (-1725 2975)(-1725 2925);
WIRE 16 -1 (-1725 2975)(-1975 2975);
WIRE 16 -1 (-1725 2925)(-1725 2875);
WIRE 16 -1 (-1725 2925)(-1975 2925);
WIRE 16 -1 (-1725 2875)(-1725 2825);
WIRE 16 -1 (-1725 2875)(-1975 2875);
WIRE 16 -1 (-1725 2825)(-1725 2775);
WIRE 16 -1 (-1725 2825)(-1975 2825);
WIRE 16 -1 (-1725 2775)(-1725 2725);
WIRE 16 -1 (-1725 2775)(-1975 2775);
WIRE 16 -1 (-1725 2725)(-1725 2675);
WIRE 16 -1 (-1725 2725)(-1975 2725);
WIRE 16 -1 (-1725 2675)(-1725 2625);
WIRE 16 -1 (-1725 2675)(-1975 2675);
WIRE 16 -1 (-1725 2625)(-1725 2575);
WIRE 16 -1 (-1725 2625)(-1975 2625);
WIRE 16 -1 (-1725 2575)(-1725 2525);
WIRE 16 -1 (-1725 2575)(-1975 2575);
WIRE 16 -1 (-1725 2525)(-1725 2475);
WIRE 16 -1 (-1725 2525)(-1975 2525);
WIRE 16 -1 (-1725 2475)(-1725 2425);
WIRE 16 -1 (-1725 2475)(-1975 2475);
WIRE 16 -1 (-1725 2425)(-1725 2375);
WIRE 16 -1 (-1725 2425)(-1975 2425);
WIRE 16 -1 (-1725 2375)(-1725 2325);
WIRE 16 -1 (-1725 2375)(-1975 2375);
WIRE 16 -1 (-1725 2325)(-1725 2275);
WIRE 16 -1 (-1725 2325)(-1975 2325);
WIRE 16 -1 (-1725 2275)(-1725 2225);
WIRE 16 -1 (-1725 2275)(-1975 2275);
WIRE 16 -1 (-1725 2225)(-1725 2175);
WIRE 16 -1 (-1725 2225)(-1975 2225);
WIRE 16 -1 (-1725 2175)(-1725 2125);
WIRE 16 -1 (-1725 2175)(-1975 2175);
WIRE 16 -1 (-1725 2125)(-1725 2075);
WIRE 16 -1 (-1725 2125)(-1975 2125);
WIRE 16 -1 (-1725 2075)(-1725 2025);
WIRE 16 -1 (-1725 2075)(-1975 2075);
WIRE 16 -1 (-1725 2025)(-1725 1975);
WIRE 16 -1 (-1725 2025)(-1975 2025);
WIRE 16 -1 (-1725 1975)(-1725 1925);
WIRE 16 -1 (-1725 1975)(-1975 1975);
WIRE 16 -1 (-1725 1925)(-1725 1875);
WIRE 16 -1 (-1725 1925)(-1975 1925);
WIRE 16 -1 (-1725 1875)(-1725 1825);
WIRE 16 -1 (-1725 1875)(-1975 1875);
WIRE 16 -1 (-1725 1825)(-1725 1775);
WIRE 16 -1 (-1725 1825)(-1975 1825);
WIRE 16 -1 (-1725 1775)(-1725 1725);
WIRE 16 -1 (-1725 1775)(-1975 1775);
WIRE 16 -1 (-1725 1725)(-1725 1675);
WIRE 16 -1 (-1725 1725)(-1975 1725);
WIRE 16 -1 (-1725 1675)(-1725 1625);
WIRE 16 -1 (-1725 1675)(-1975 1675);
WIRE 16 -1 (-1725 1625)(-1725 1575);
WIRE 16 -1 (-1725 1625)(-1975 1625);
WIRE 16 -1 (-1725 1575)(-1725 1525);
WIRE 16 -1 (-1725 1575)(-1975 1575);
WIRE 16 -1 (-1725 1525)(-1725 1475);
WIRE 16 -1 (-1725 1525)(-1975 1525);
WIRE 16 -1 (-1725 1475)(-1725 1425);
WIRE 16 -1 (-1725 1475)(-1975 1475);
WIRE 16 -1 (-1725 1425)(-1725 1375);
WIRE 16 -1 (-1725 1425)(-1975 1425);
WIRE 16 -1 (-1725 1375)(-1725 1325);
WIRE 16 -1 (-1725 1375)(-1975 1375);
WIRE 16 -1 (-1725 1325)(-1725 1275);
WIRE 16 -1 (-1725 1325)(-1975 1325);
WIRE 16 -1 (-1725 1275)(-1725 1225);
WIRE 16 -1 (-1725 1275)(-1975 1275);
WIRE 16 -1 (-1725 1225)(-1975 1225);
WIRE 16 -1 (-500 650)(-500 575);
WIRE 16 -1 (-1100 1500)(-1100 1650);
WIRE 16 -1 (-500 1300)(-500 1450);
WIRE 16 -1 (-1100 1025)(-1975 1025);
WIRE 16 -1 (-1100 1125)(-1975 1125);
FORCEPROP 0 LAST SIG_NAME VSENSE_VCCINR2PMAX_CPU1
J 0
(-1775 1135);
DISPLAY 0.617021 (-1775 1135);
PAINT ORANGE (-1775 1135);
FORCEPROP 2 LASTPROP $XRERR UNIQUE?
J 0
(-2015 1135);
DISPLAY 0.638298 (-2015 1135);
PAINT MONO (-2015 1135);
DISPLAY INVISIBLE (-2015 1135);
WIRE 16 -1 (-1100 1125)(-1100 1025);
WIRE 16 -1 (-1100 1125)(-1100 1300);
WIRE 16 -1 (-500 925)(-1975 925);
FORCEPROP 0 LAST SIG_NAME VSENSE_PMAX_CPU1
J 0
(-1775 935);
DISPLAY 0.617021 (-1775 935);
PAINT ORANGE (-1775 935);
FORCEPROP 2 LASTPROP $XRERR UNIQUE?
J 0
(-2015 935);
DISPLAY 0.638298 (-2015 935);
PAINT MONO (-2015 935);
DISPLAY INVISIBLE (-2015 935);
WIRE 16 -1 (-500 850)(-500 925);
WIRE 16 -1 (-500 925)(-500 1100);
WIRE 16 -1 (-925 825)(-1975 825);
FORCEPROP 0 LAST SIG_NAME VSENSE_PVCCIN_CPU1_SKT_VSEN
J 0
(-1775 834);
DISPLAY 0.617021 (-1775 834);
PAINT ORANGE (-1775 834);
WIRE 16 -1 (-925 775)(-1975 775);
FORCEPROP 0 LAST SIG_NAME VSENSE_PVCCIN_CPU1_SKT_VRTN
J 0
(-1775 775);
DISPLAY 0.617021 (-1775 775);
PAINT ORANGE (-1775 775);
DOT 1 (-7325 875);
DOT 1 (-7325 975);
DOT 1 (-7325 925);
DOT 1 (-7325 1025);
DOT 1 (-7325 1075);
DOT 1 (-7325 1125);
DOT 1 (-7325 1175);
DOT 1 (-7325 1225);
DOT 1 (-7325 1275);
DOT 1 (-7325 1375);
DOT 1 (-7325 1325);
DOT 1 (-7325 1425);
DOT 1 (-7325 1475);
DOT 1 (-7325 1525);
DOT 1 (-7325 1625);
DOT 1 (-7325 1575);
DOT 1 (-7325 1675);
DOT 1 (-7325 1725);
DOT 1 (-7325 1775);
DOT 1 (-7325 1875);
DOT 1 (-7325 1825);
DOT 1 (-7325 1925);
DOT 1 (-7325 1975);
DOT 1 (-7325 2025);
DOT 1 (-7325 2075);
DOT 1 (-7325 2125);
DOT 1 (-7325 2175);
DOT 1 (-7325 2275);
DOT 1 (-7325 2225);
DOT 1 (-7325 2325);
DOT 1 (-7325 2375);
DOT 1 (-7325 2425);
DOT 1 (-7325 2525);
DOT 1 (-7325 2475);
DOT 1 (-7325 2575);
DOT 1 (-7325 2625);
DOT 1 (-7325 2675);
DOT 1 (-7325 2775);
DOT 1 (-7325 2725);
DOT 1 (-7325 2825);
DOT 1 (-7325 2875);
DOT 1 (-7325 2925);
DOT 1 (-7325 3025);
DOT 1 (-7325 2975);
DOT 1 (-7325 3075);
DOT 1 (-7325 3125);
DOT 1 (-7325 3175);
DOT 1 (-7325 3225);
DOT 1 (-7325 3275);
DOT 1 (-7325 3325);
DOT 1 (-7325 3425);
DOT 1 (-7325 3375);
DOT 1 (-7325 3475);
DOT 1 (-7325 3525);
DOT 1 (-7325 3575);
DOT 1 (-7325 3675);
DOT 1 (-7325 3625);
DOT 1 (-7325 3725);
DOT 1 (-7325 3775);
DOT 1 (-7325 3825);
DOT 1 (-7325 3925);
DOT 1 (-7325 3875);
DOT 1 (-7325 3975);
DOT 1 (-7325 4025);
DOT 1 (-7325 4075);
DOT 1 (-5425 875);
DOT 1 (-5425 925);
DOT 1 (-5425 975);
DOT 1 (-5425 1025);
DOT 1 (-5425 1075);
DOT 1 (-5425 1125);
DOT 1 (-5425 1175);
DOT 1 (-5425 1225);
DOT 1 (-5425 1275);
DOT 1 (-5425 1375);
DOT 1 (-5425 1325);
DOT 1 (-5425 1425);
DOT 1 (-5425 1475);
DOT 1 (-5425 1525);
DOT 1 (-5425 1625);
DOT 1 (-5425 1575);
DOT 1 (-5425 1675);
DOT 1 (-5425 1725);
DOT 1 (-5425 1775);
DOT 1 (-5425 1875);
DOT 1 (-5425 1825);
DOT 1 (-5425 1925);
DOT 1 (-5425 1975);
DOT 1 (-5425 2025);
DOT 1 (-5425 2075);
DOT 1 (-5425 2125);
DOT 1 (-5425 2175);
DOT 1 (-5425 2275);
DOT 1 (-5425 2225);
DOT 1 (-5425 2325);
DOT 1 (-5425 2375);
DOT 1 (-5425 2425);
DOT 1 (-5425 2525);
DOT 1 (-5425 2475);
DOT 1 (-5425 2575);
DOT 1 (-5425 2625);
DOT 1 (-5425 2675);
DOT 1 (-5425 2775);
DOT 1 (-5425 2725);
DOT 1 (-5425 2825);
DOT 1 (-5425 2875);
DOT 1 (-5425 2925);
DOT 1 (-5425 3025);
DOT 1 (-5425 2975);
DOT 1 (-5425 3075);
DOT 1 (-5425 3125);
DOT 1 (-5425 3175);
DOT 1 (-5425 3225);
DOT 1 (-5425 3275);
DOT 1 (-5425 3325);
DOT 1 (-5425 3425);
DOT 1 (-5425 3375);
DOT 1 (-5425 3475);
DOT 1 (-5425 3525);
DOT 1 (-5425 3575);
DOT 1 (-5425 3675);
DOT 1 (-5425 3625);
DOT 1 (-5425 3725);
DOT 1 (-5425 3775);
DOT 1 (-5425 3825);
DOT 1 (-5425 3925);
DOT 1 (-5425 3875);
DOT 1 (-5425 3975);
DOT 1 (-5425 4025);
DOT 1 (-5425 4075);
DOT 1 (-7325 4175);
DOT 1 (-7325 4125);
DOT 1 (-7325 4225);
DOT 1 (-5425 4175);
DOT 1 (-5425 4125);
DOT 1 (-5425 4225);
DOT 1 (-3600 875);
DOT 1 (-3600 925);
DOT 1 (-3600 975);
DOT 1 (-3600 1025);
DOT 1 (-3600 1075);
DOT 1 (-3600 1125);
DOT 1 (-3600 1175);
DOT 1 (-3600 1225);
DOT 1 (-3600 1275);
DOT 1 (-3600 1375);
DOT 1 (-3600 1325);
DOT 1 (-3600 1425);
DOT 1 (-3600 1475);
DOT 1 (-3600 1525);
DOT 1 (-3600 1625);
DOT 1 (-3600 1575);
DOT 1 (-3600 1675);
DOT 1 (-3600 1725);
DOT 1 (-3600 1775);
DOT 1 (-3600 1875);
DOT 1 (-3600 1825);
DOT 1 (-3600 1925);
DOT 1 (-3600 1975);
DOT 1 (-3600 2025);
DOT 1 (-3600 2075);
DOT 1 (-3600 2125);
DOT 1 (-3600 2175);
DOT 1 (-3600 2275);
DOT 1 (-3600 2225);
DOT 1 (-3600 2325);
DOT 1 (-3600 2375);
DOT 1 (-3600 2425);
DOT 1 (-3600 2525);
DOT 1 (-3600 2475);
DOT 1 (-3600 2575);
DOT 1 (-3600 2625);
DOT 1 (-3600 2675);
DOT 1 (-3600 2725);
DOT 1 (-3600 2775);
DOT 1 (-3600 2825);
DOT 1 (-3600 2875);
DOT 1 (-3600 2925);
DOT 1 (-3600 3025);
DOT 1 (-3600 2975);
DOT 1 (-3600 3075);
DOT 1 (-3600 3125);
DOT 1 (-3600 3175);
DOT 1 (-3600 3225);
DOT 1 (-3600 3275);
DOT 1 (-3600 3325);
DOT 1 (-3600 3425);
DOT 1 (-3600 3375);
DOT 1 (-3600 3475);
DOT 1 (-3600 3525);
DOT 1 (-3600 3575);
DOT 1 (-3600 3675);
DOT 1 (-3600 3625);
DOT 1 (-3600 3725);
DOT 1 (-3600 3775);
DOT 1 (-3600 3825);
DOT 1 (-3600 3925);
DOT 1 (-3600 3875);
DOT 1 (-3600 3975);
DOT 1 (-3600 4025);
DOT 1 (-3600 4075);
DOT 1 (-1725 1275);
DOT 1 (-1725 1375);
DOT 1 (-1725 1325);
DOT 1 (-1725 1425);
DOT 1 (-1725 1475);
DOT 1 (-1725 1525);
DOT 1 (-1725 1625);
DOT 1 (-1725 1575);
DOT 1 (-1725 1675);
DOT 1 (-1725 1725);
DOT 1 (-1725 1775);
DOT 1 (-1725 1825);
DOT 1 (-1725 1875);
DOT 1 (-1725 1925);
DOT 1 (-1725 2025);
DOT 1 (-1725 1975);
DOT 1 (-1100 1125);
DOT 1 (-500 925);
DOT 1 (-1725 2125);
DOT 1 (-1725 2075);
DOT 1 (-1725 2175);
DOT 1 (-1725 2275);
DOT 1 (-1725 2225);
DOT 1 (-1725 2325);
DOT 1 (-1725 2375);
DOT 1 (-1725 2425);
DOT 1 (-1725 2525);
DOT 1 (-1725 2475);
DOT 1 (-1725 2625);
DOT 1 (-1725 2575);
DOT 1 (-1725 2675);
DOT 1 (-1725 2775);
DOT 1 (-1725 2725);
DOT 1 (-1725 2825);
DOT 1 (-1725 2925);
DOT 1 (-1725 2875);
DOT 1 (-1725 2975);
DOT 1 (-1725 3025);
DOT 1 (-1725 3075);
DOT 1 (-1725 3125);
DOT 1 (-1725 3175);
DOT 1 (-1725 3225);
DOT 1 (-1725 3325);
DOT 1 (-1725 3275);
DOT 1 (-1725 3425);
DOT 1 (-1725 3375);
DOT 1 (-1725 3525);
DOT 1 (-1725 3575);
DOT 1 (-1725 3475);
DOT 1 (-1725 3625);
DOT 1 (-1725 3675);
DOT 1 (-1725 3725);
DOT 1 (-1725 3825);
DOT 1 (-1725 3775);
DOT 1 (-1725 3875);
DOT 1 (-1725 3925);
DOT 1 (-1725 3975);
DOT 1 (-1725 4075);
DOT 1 (-3600 4175);
DOT 1 (-3600 4125);
DOT 1 (-3600 4225);
DOT 1 (-1725 4125);
DOT 1 (-1725 4175);
DOT 1 (-1725 4225);
DOT 1 (-1725 4025);
FORCENOTE
ROOM=CPU1
(-7950 300) 0;
DISPLAY LEFT (-7950 300);
DISPLAY 1.723404 (-7950 300);
PAINT PURPLE (-7950 300);
FORCENOTE
BOM_COST=PROC_SOCKET
(-7950 175) 0;
DISPLAY LEFT (-7950 175);
DISPLAY 1.723404 (-7950 175);
PAINT PURPLE (-7950 175);
QUIT
